G04 ================== begin FILE IDENTIFICATION RECORD ==================*
G04 Layout Name:  D:/<user>/Wistron_project/16315-1/gbr/16315-1.brd*
G04 Film Name:    DP_REF_L8*
G04 File Format:  Gerber RS274X*
G04 File Origin:  Cadence Allegro 16.5-S056*
G04 Origin Date:  Fri Jun 09 15:32:52 2017*
G04 *
G04 Layer:  BOARD GEOMETRY/DP_REF_L8_TBL*
G04 Layer:  BOARD GEOMETRY/DP_REF_L8_L8*
G04 Layer:  BOARD GEOMETRY/PANEL_OUTLINE*
G04 *
G04 Offset:    (0.00 0.00)*
G04 Mirror:    No*
G04 Mode:      Positive*
G04 Rotation:  0*
G04 FullContactRelief:  No*
G04 UndefLineWidth:     6.00*
G04 ================== end FILE IDENTIFICATION RECORD ====================*
%FSLAX35Y35*MOIN*%
%IR0*IPPOS*OFA0.00000B0.00000*MIA0B0*SFA1.00000B1.00000*%
%ADD10C,.02*%
%ADD11C,.004*%
%ADD12C,.005*%
%ADD13C,.006*%
G75*
%LPD*%
G75*
G54D10*
G01X1985143Y1554618D02*
X2772643D01*
G01X1985143Y1519968D02*
X2772643D01*
G01X1985143Y1623918D02*
Y1519968D01*
G01Y1589268D02*
X2772643D01*
G01X1985143Y1623918D02*
X2772643D01*
G01X2160143D02*
Y1519968D01*
G01X2457643Y1623918D02*
Y1519968D01*
G01X2562643Y1623918D02*
Y1519968D01*
G01X2772643Y1623918D02*
Y1519968D01*
G54D11*
G01X131027Y188642D02*
X128388D01*
G01X131239Y187342D02*
X128388D01*
G01X211200Y215382D02*
X131027Y188642D01*
G01X291948Y240941D02*
X131239Y187342D01*
G01X291948Y240941D02*
X131239Y187342D01*
G01D02*
X128388D01*
G01X131027Y188642D02*
X128388D01*
G01X291948Y240941D02*
X131239Y187342D01*
G01X211200Y215382D02*
X131027Y188642D01*
G01X132514Y641398D02*
X128388D01*
G01Y640098D02*
X132857D01*
G01X142876Y647264D02*
X132514Y641398D01*
G01X132857Y640098D02*
X143799Y646292D01*
G01X247669Y811758D02*
X142876Y647264D01*
G01X143799Y646292D02*
X248611Y810816D01*
G01X143799Y646292D02*
X248611Y810816D01*
G01X247669Y811758D02*
X142876Y647264D01*
G01X132857Y640098D02*
X143799Y646292D01*
G01X142876Y647264D02*
X132514Y641398D01*
G01X128388Y640098D02*
X132857D01*
G01X132514Y641398D02*
X128388D01*
G01X130635Y1094154D02*
X128388D01*
G01Y1092854D02*
X130778D01*
G01X131627Y1094375D02*
X130635Y1094154D01*
G01X130778Y1092854D02*
X132132Y1093154D01*
G01X140715Y1100161D02*
X131627Y1094374D01*
G01X136869Y1096170D02*
X141657Y1099219D01*
G01X132132Y1093154D02*
X136869Y1096170D01*
G01X154686Y1122089D02*
X140715Y1100161D01*
G01X141657Y1099219D02*
X155628Y1121147D01*
G01X172773Y1133612D02*
X154686Y1122089D01*
G01X155628Y1121147D02*
X173278Y1132392D01*
G01X155628Y1121147D02*
X173278Y1132392D01*
G01X172773Y1133612D02*
X154686Y1122089D01*
G01X141657Y1099219D02*
X155628Y1121147D01*
G01X154686Y1122089D02*
X140715Y1100161D01*
G01X136869Y1096170D02*
X141657Y1099219D01*
G01X140715Y1100161D02*
X131627Y1094374D01*
G01X132132Y1093154D02*
X136869Y1096170D01*
G01X140715Y1100161D02*
X131627Y1094374D01*
G01X130778Y1092854D02*
X132132Y1093154D01*
G01X131627Y1094375D02*
X130635Y1094154D01*
G01X128388Y1092854D02*
X130778D01*
G01X130635Y1094154D02*
X128388D01*
G01X291373Y242120D02*
X211200Y215381D01*
G01X291373Y242120D02*
X211200Y215381D01*
G01X866532Y1287395D02*
X172773Y1133612D01*
G01X173278Y1132392D02*
X867039Y1286175D01*
G01X173278Y1132392D02*
X867039Y1286175D01*
G01X866532Y1287395D02*
X172773Y1133612D01*
G01X256179Y188642D02*
X252600D01*
G01X256465Y187342D02*
X252600D01*
G01X283071Y201064D02*
X256179Y188642D01*
G01X310625Y212357D02*
X256465Y187342D01*
G01X310625Y212357D02*
X256465Y187342D01*
G01D02*
X252600D01*
G01X256179Y188642D02*
X252600D01*
G01X310625Y212357D02*
X256465Y187342D01*
G01X283071Y201064D02*
X256179Y188642D01*
G01X255872Y641398D02*
X252600D01*
G01Y640098D02*
X256252D01*
G01X259946Y643993D02*
X255872Y641398D01*
G01X256252Y640098D02*
X260888Y643051D01*
G01X270251Y660161D02*
X259946Y643993D01*
G01X260888Y643051D02*
X271470Y659653D01*
G01X260888Y643051D02*
X271470Y659653D01*
G01X270251Y660161D02*
X259946Y643993D01*
G01X256252Y640098D02*
X260888Y643051D01*
G01X259946Y643993D02*
X255872Y641398D01*
G01X252600Y640098D02*
X256252D01*
G01X255872Y641398D02*
X252600D01*
G01X364199Y886076D02*
X247669Y811758D01*
G01X248611Y810816D02*
X364693Y884849D01*
G01X248611Y810816D02*
X364693Y884849D01*
G01X364199Y886076D02*
X247669Y811758D01*
G01X256464Y1094154D02*
X252600D01*
G01Y1092854D02*
X256601D01*
G01X273616Y1097802D02*
X256464Y1094154D01*
G01X256601Y1092854D02*
X291274Y1100226D01*
G01X256601Y1092854D02*
X291274Y1100226D01*
G01X256601Y1092854D02*
X291274Y1100226D01*
G01X273616Y1097802D02*
X256464Y1094154D01*
G01X252600Y1092854D02*
X256601D01*
G01X256464Y1094154D02*
X252600D01*
G01X309962Y213483D02*
X283071Y201063D01*
G01X673118Y477897D02*
X310625Y212357D01*
G01X309962Y213483D02*
X283071Y201063D01*
G01X673118Y477897D02*
X310625Y212357D01*
G01X672184Y478826D02*
X309962Y213483D01*
G01X672184Y478826D02*
X309962Y213483D01*
G01X674977Y496693D02*
X291373Y242120D01*
G01X675893Y495739D02*
X291948Y240941D01*
G01X675893Y495739D02*
X291948Y240941D01*
G01X674977Y496693D02*
X291373Y242120D01*
G01X299666Y790448D02*
X270251Y660161D01*
G01X271470Y659653D02*
X300885Y789940D01*
G01X271470Y659653D02*
X300885Y789940D01*
G01X299666Y790448D02*
X270251Y660161D01*
G01X336802Y848743D02*
X299666Y790448D01*
G01X300885Y789940D02*
X350237Y867413D01*
G01X300885Y789940D02*
X350237Y867413D01*
G01X300885Y789940D02*
X350237Y867413D01*
G01X336802Y848743D02*
X299666Y790448D01*
G01X290768Y1101448D02*
X273616Y1097801D01*
G01X413728Y1181301D02*
X290768Y1101448D01*
G01X291274Y1100226D02*
X414239Y1180082D01*
G01X291274Y1100226D02*
X414239Y1180082D01*
G01X413728Y1181301D02*
X290768Y1101448D01*
G01D02*
X273616Y1097801D01*
G01X349294Y868355D02*
X336802Y848743D01*
G01X367334Y879863D02*
X349294Y868355D01*
G01X359033Y873025D02*
X367828Y878636D01*
G01X350237Y867413D02*
X359033Y873025D01*
G01D02*
X367828Y878636D01*
G01X367334Y879863D02*
X349294Y868355D01*
G01X350237Y867413D02*
X359033Y873025D01*
G01X367334Y879863D02*
X349294Y868355D01*
G01D02*
X336802Y848743D01*
G01X380142Y188642D02*
X376813D01*
G01X380485Y187342D02*
X376813D01*
G01X383760Y190691D02*
X380142Y188642D01*
G01X384677Y189716D02*
X380485Y187342D01*
G01X464336Y314756D02*
X383760Y190691D01*
G01X465294Y313843D02*
X384677Y189716D01*
G01X380485Y187342D02*
X376813D01*
G01X380142Y188642D02*
X376813D01*
G01X384677Y189716D02*
X380485Y187342D01*
G01X383760Y190691D02*
X380142Y188642D01*
G01X465294Y313843D02*
X384677Y189716D01*
G01X464336Y314756D02*
X383760Y190691D01*
G01X380276Y641398D02*
X376813D01*
G01X380419Y640098D02*
X376813D01*
G01X382791Y641957D02*
X380276Y641398D01*
G01X383296Y640737D02*
X380419Y640098D01*
G01X385363Y643596D02*
X382791Y641957D01*
G01X386306Y642654D02*
X383296Y640737D01*
G01X397305Y662398D02*
X385363Y643596D01*
G01X398525Y661894D02*
X386306Y642654D01*
G01X380419Y640098D02*
X376813D01*
G01X380276Y641398D02*
X376813D01*
G01X383296Y640737D02*
X380419Y640098D01*
G01X382791Y641957D02*
X380276Y641398D01*
G01X386306Y642654D02*
X383296Y640737D01*
G01X385363Y643596D02*
X382791Y641957D01*
G01X398525Y661894D02*
X386306Y642654D01*
G01X397305Y662398D02*
X385363Y643596D01*
G01X408143Y711428D02*
X397305Y662398D01*
G01X409413Y711147D02*
X398525Y661894D01*
G01X409413Y711147D02*
X398525Y661894D01*
G01X408143Y711428D02*
X397305Y662398D01*
G01X440216Y856517D02*
X408143Y711428D01*
G01X441391Y855806D02*
X409413Y711147D01*
G01X441391Y855806D02*
X409413Y711147D01*
G01X440216Y856517D02*
X408143Y711428D01*
G01X568147Y920060D02*
X367334Y879863D01*
G01X367828Y878636D02*
X568604Y918825D01*
G01X367828Y878636D02*
X568604Y918825D01*
G01X568147Y920060D02*
X367334Y879863D01*
G01X565047Y926276D02*
X364199Y886076D01*
G01X364693Y884849D02*
X565504Y925041D01*
G01X364693Y884849D02*
X565504Y925041D01*
G01X565047Y926276D02*
X364199Y886076D01*
G01X376813Y1094154D02*
X431153D01*
G01X376813Y1092854D02*
X431296D01*
G01X376813D02*
X431296D01*
G01X376813Y1094154D02*
X431153D01*
G01X484653Y893970D02*
X440216Y856517D01*
G01X485242Y892765D02*
X441391Y855806D01*
G01X485242Y892765D02*
X441391Y855806D01*
G01X484653Y893970D02*
X440216Y856517D01*
G01X431153Y1094154D02*
X464464Y1101538D01*
G01X431296Y1092854D02*
X464969Y1100318D01*
G01X431296Y1092854D02*
X464969Y1100318D01*
G01X431153Y1094154D02*
X464464Y1101538D01*
G01X869360Y1282308D02*
X413728Y1181301D01*
G01X414239Y1180082D02*
X869865Y1281088D01*
G01X414239Y1180082D02*
X869865Y1281088D01*
G01X869360Y1282308D02*
X413728Y1181301D01*
G01X503371Y188642D02*
X501025D01*
G01Y187342D02*
X503736D01*
G01X505058Y189670D02*
X503371Y188642D01*
G01X503736Y187342D02*
X506001Y188721D01*
G01X535919Y239595D02*
X505058Y189670D01*
G01X506001Y188721D02*
X536872Y238663D01*
G01X506001Y188721D02*
X536872Y238663D01*
G01X535919Y239595D02*
X505058Y189670D01*
G01X503736Y187342D02*
X506001Y188721D01*
G01X505058Y189670D02*
X503371Y188642D01*
G01X501025Y187342D02*
X503736D01*
G01X503371Y188642D02*
X501025D01*
G01X628931Y433368D02*
X464336Y314756D01*
G01X794666Y551200D02*
X465294Y313843D01*
G01X794666Y551200D02*
X465294Y313843D01*
G01X794666Y551200D02*
X465294Y313843D01*
G01X628931Y433368D02*
X464336Y314756D01*
G01X504422Y641398D02*
X501025D01*
G01Y640098D02*
X504565D01*
G01X505583Y641656D02*
X504422Y641398D01*
G01X504565Y640098D02*
X506088Y640435D01*
G01X508532Y643534D02*
X505583Y641655D01*
G01X506088Y640435D02*
X509474Y642592D01*
G01X506088Y640435D02*
X509474Y642592D01*
G01X508532Y643534D02*
X505583Y641655D01*
G01X504565Y640098D02*
X506088Y640435D01*
G01X505583Y641656D02*
X504422Y641398D01*
G01X501025Y640098D02*
X504565D01*
G01X504422Y641398D02*
X501025D01*
G01X573377Y912712D02*
X484653Y893970D01*
G01X573861Y911485D02*
X485242Y892765D01*
G01X573861Y911485D02*
X485242Y892765D01*
G01X573377Y912712D02*
X484653Y893970D01*
G01X513568Y1094154D02*
X501025D01*
G01Y1092854D02*
X513711D01*
G01X501025D02*
X513711D01*
G01X513568Y1094154D02*
X501025D01*
G01X464464Y1101538D02*
X665332Y1229508D01*
G01X464969Y1100318D02*
X665837Y1228288D01*
G01X464969Y1100318D02*
X665837Y1228288D01*
G01X464464Y1101538D02*
X665332Y1229508D01*
G01X613942Y290266D02*
X535919Y239595D01*
G01X536872Y238663D02*
X614847Y289302D01*
G01X536872Y238663D02*
X614847Y289302D01*
G01X613942Y290266D02*
X535919Y239595D01*
G01X531762Y679987D02*
X508532Y643534D01*
G01X509474Y642592D02*
X532982Y679482D01*
G01X509474Y642592D02*
X532982Y679482D01*
G01X531762Y679987D02*
X508532Y643534D01*
G01X559695Y805972D02*
X531762Y679987D01*
G01X532982Y679482D02*
X560915Y805467D01*
G01X532982Y679482D02*
X560915Y805467D01*
G01X559695Y805972D02*
X531762Y679987D01*
G01X532235Y1098294D02*
X513568Y1094154D01*
G01X513711Y1092854D02*
X532740Y1097074D01*
G01X762051Y1244716D02*
X532235Y1098294D01*
G01X532740Y1097074D02*
X762556Y1243496D01*
G01X532740Y1097074D02*
X762556Y1243496D01*
G01X762051Y1244716D02*
X532235Y1098294D01*
G01X513711Y1092854D02*
X532740Y1097074D01*
G01X532235Y1098294D02*
X513568Y1094154D01*
G01X648607Y945544D02*
X559695Y805972D01*
G01X560915Y805467D02*
X627375Y909793D01*
G01X648607Y945544D02*
X559695Y805972D01*
G01X560915Y805467D02*
X627375Y909793D01*
G01X648607Y945544D02*
X559695Y805972D01*
G01X575198Y913812D02*
X573377Y912712D01*
G01X575853Y912688D02*
X573861Y911485D01*
G01X797222Y1038410D02*
X575198Y913812D01*
G01X798138Y1037433D02*
X575853Y912688D01*
G01D02*
X573861Y911485D01*
G01X575198Y913812D02*
X573377Y912712D01*
G01X798138Y1037433D02*
X575853Y912688D01*
G01X797222Y1038410D02*
X575198Y913812D01*
G01X791916Y1045640D02*
X568147Y920060D01*
G01X568604Y918825D02*
X792832Y1044663D01*
G01X568604Y918825D02*
X792832Y1044663D01*
G01X791916Y1045640D02*
X568147Y920060D01*
G01X790150Y1052605D02*
X565047Y926276D01*
G01X565504Y925041D02*
X791066Y1051627D01*
G01X565504Y925041D02*
X791066Y1051627D01*
G01X790150Y1052605D02*
X565047Y926276D01*
G01X629430Y188642D02*
X625238D01*
G01X629773Y187342D02*
X625238D01*
G01X633278Y190821D02*
X629430Y188642D01*
G01X634165Y189829D02*
X629773Y187342D01*
G01X757005Y361844D02*
X633278Y190821D01*
G01X758206Y361285D02*
X634165Y189829D01*
G01X629773Y187342D02*
X625238D01*
G01X629430Y188642D02*
X625238D01*
G01X634165Y189829D02*
X629773Y187342D01*
G01X633278Y190821D02*
X629430Y188642D01*
G01X758206Y361285D02*
X634165Y189829D01*
G01X757005Y361844D02*
X633278Y190821D01*
G01X795572Y534638D02*
X613942Y290266D01*
G01X614847Y289302D02*
X705801Y411675D01*
G01X795572Y534638D02*
X613942Y290266D01*
G01X614847Y289302D02*
X705801Y411675D01*
G01X795572Y534638D02*
X613942Y290266D01*
G01X793523Y551980D02*
X628931Y433368D01*
G01X793523Y551980D02*
X628931Y433368D01*
G01X628067Y641398D02*
X625238D01*
G01Y640098D02*
X628210D01*
G01X630831Y642012D02*
X628067Y641398D01*
G01X628210Y640098D02*
X631336Y640791D01*
G01X636805Y645814D02*
X630831Y642011D01*
G01X631336Y640791D02*
X637740Y644868D01*
G01X769036Y848328D02*
X636805Y645814D01*
G01X637740Y644868D02*
X770255Y847817D01*
G01X637740Y644868D02*
X770255Y847817D01*
G01X769036Y848328D02*
X636805Y645814D01*
G01X631336Y640791D02*
X637740Y644868D01*
G01X636805Y645814D02*
X630831Y642011D01*
G01X628210Y640098D02*
X631336Y640791D01*
G01X630831Y642012D02*
X628067Y641398D01*
G01X625238Y640098D02*
X628210D01*
G01X628067Y641398D02*
X625238D01*
G01X627375Y909793D02*
X649528Y944570D01*
G01X627375Y909793D02*
X649528Y944570D01*
G01X801133Y1031142D02*
X648607Y945544D01*
G01X649528Y944570D02*
X725789Y987368D01*
G01X801133Y1031142D02*
X648607Y945544D01*
G01X649528Y944570D02*
X725789Y987368D01*
G01X801133Y1031142D02*
X648607Y945544D01*
G01X637669Y1099738D02*
X680936Y1167645D01*
G01X638611Y1098796D02*
X681878Y1166703D01*
G01X629709Y1094667D02*
X637669Y1099738D01*
G01X630214Y1093447D02*
X638611Y1098796D01*
G01X627395Y1094154D02*
X629709Y1094667D01*
G01X627538Y1092854D02*
X630214Y1093447D01*
G01X625238Y1094154D02*
X627395D01*
G01X625238Y1092854D02*
X627538D01*
G01X638611Y1098796D02*
X681878Y1166703D01*
G01X637669Y1099738D02*
X680936Y1167645D01*
G01X630214Y1093447D02*
X638611Y1098796D01*
G01X629709Y1094667D02*
X637669Y1099738D01*
G01X627538Y1092854D02*
X630214Y1093447D01*
G01X627395Y1094154D02*
X629709Y1094667D01*
G01X625238Y1092854D02*
X627538D01*
G01X625238Y1094154D02*
X627395D01*
G01X761960Y602916D02*
X672184Y478825D01*
G01X763176Y602378D02*
X673118Y477897D01*
G01X763176Y602378D02*
X673118Y477897D01*
G01X761960Y602916D02*
X672184Y478825D01*
G01X756192Y608952D02*
X674977Y496693D01*
G01X757408Y608414D02*
X675893Y495739D01*
G01X757408Y608414D02*
X675893Y495739D01*
G01X756192Y608952D02*
X674977Y496693D01*
G01X681878Y1166703D02*
X805301Y1245333D01*
G01X681878Y1166703D02*
X805301Y1245333D01*
G01X680936Y1167645D02*
X804603Y1246430D01*
G01X681878Y1166703D02*
X805301Y1245333D01*
G01X681878Y1166703D02*
X805301Y1245333D01*
G01X680936Y1167645D02*
X804603Y1246430D01*
G01X665332Y1229508D02*
X869857Y1274854D01*
G01X665837Y1228288D02*
X767875Y1250910D01*
G01X665332Y1229508D02*
X869857Y1274854D01*
G01X665837Y1228288D02*
X767875Y1250910D01*
G01X665332Y1229508D02*
X869857Y1274854D01*
G01X745360Y299665D02*
X764638Y237790D01*
G01X746711Y299702D02*
X765979Y237860D01*
G01X856966Y742857D02*
X745360Y299665D01*
G01X858307Y742854D02*
X746711Y299702D01*
G01D02*
X765979Y237860D01*
G01X745360Y299665D02*
X764638Y237790D01*
G01X858307Y742854D02*
X746711Y299702D01*
G01X856966Y742857D02*
X745360Y299665D01*
G01X705801Y411675D02*
X796771Y534070D01*
G01X705801Y411675D02*
X796771Y534070D01*
G01X742316Y698776D02*
X754476Y644365D01*
G01X755824Y644297D02*
X743648Y698782D01*
G01X755824Y644297D02*
X743648Y698782D01*
G01X742316Y698776D02*
X754476Y644365D01*
G01X788205Y912286D02*
X742316Y698776D01*
G01X743648Y698782D02*
X789443Y911858D01*
G01X743648Y698782D02*
X789443Y911858D01*
G01X788205Y912286D02*
X742316Y698776D01*
G01X725789Y987368D02*
X802049Y1030165D01*
G01X725789Y987368D02*
X802049Y1030165D01*
G01X751785Y188642D02*
X749451D01*
G01X752128Y187342D02*
X749451D01*
G01X754388Y190116D02*
X751785Y188642D01*
G01X755299Y189137D02*
X752128Y187342D01*
G01X755357Y191575D02*
X754388Y190116D01*
G01X756582Y191068D02*
X755299Y189137D01*
G01X759998Y214682D02*
X755357Y191575D01*
G01X765979Y237860D02*
X756582Y191068D01*
G01X765979Y237860D02*
X756582Y191068D01*
G01X752128Y187342D02*
X749451D01*
G01X751785Y188642D02*
X749451D01*
G01X755299Y189137D02*
X752128Y187342D01*
G01X754388Y190116D02*
X751785Y188642D01*
G01X756582Y191068D02*
X755299Y189137D01*
G01X755357Y191575D02*
X754388Y190116D01*
G01X765979Y237860D02*
X756582Y191068D01*
G01X759998Y214682D02*
X755357Y191575D01*
G01X764638Y237790D02*
X759998Y214682D01*
G01X764638Y237790D02*
X759998Y214682D01*
G01X851538Y739151D02*
X757005Y361844D01*
G01X852878Y739149D02*
X758206Y361285D01*
G01X852878Y739149D02*
X758206Y361285D01*
G01X851538Y739151D02*
X757005Y361844D01*
G01X845214Y732788D02*
X795572Y534638D01*
G01X796771Y534070D02*
X846554Y732786D01*
G01X796771Y534070D02*
X846554Y732786D01*
G01X845214Y732788D02*
X795572Y534638D01*
G01X838415Y726971D02*
X793523Y551980D01*
G01X839753Y726955D02*
X794666Y551200D01*
G01X839753Y726955D02*
X794666Y551200D01*
G01X838415Y726971D02*
X793523Y551980D01*
G01X751828Y641398D02*
X749451D01*
G01Y640098D02*
X752127D01*
G01X752820Y641879D02*
X751828Y641398D01*
G01X752127Y640098D02*
X754872Y641427D01*
G01X752819Y641879D02*
X752820D01*
G01X752127Y640098D02*
X754872Y641427D01*
G01X753810Y642359D02*
X752819Y641879D01*
G01X752127Y640098D02*
X754872Y641427D01*
G01X754476Y644365D02*
X753810Y642359D01*
G01X754872Y641427D02*
X755824Y644297D01*
G01X754872Y641427D02*
X755824Y644297D01*
G01X754476Y644365D02*
X753810Y642359D01*
G01X752127Y640098D02*
X754872Y641427D01*
G01X752820Y641879D02*
X751828Y641398D01*
G01X752819Y641879D02*
X752820D01*
G01X753810Y642359D02*
X752819Y641879D01*
G01X749451Y640098D02*
X752127D01*
G01X751828Y641398D02*
X749451D01*
G01X774067Y660582D02*
X761960Y602916D01*
G01X775399Y660596D02*
X763176Y602378D01*
G01X775399Y660596D02*
X763176Y602378D01*
G01X774067Y660582D02*
X761960Y602916D01*
G01X767550Y663044D02*
X756192Y608952D01*
G01X768881Y663056D02*
X757408Y608414D01*
G01X768881Y663056D02*
X757408Y608414D01*
G01X767550Y663044D02*
X756192Y608952D01*
G01X759151Y724712D02*
X774067Y660582D01*
G01X760484Y724723D02*
X775399Y660596D01*
G01X760484Y724723D02*
X775399Y660596D01*
G01X759151Y724712D02*
X774067Y660582D01*
G01X753539Y724266D02*
X767550Y663044D01*
G01X754871Y724275D02*
X768881Y663056D01*
G01X754871Y724275D02*
X768881Y663056D01*
G01X753539Y724266D02*
X767550Y663044D01*
G01X799044Y910319D02*
X759151Y724712D01*
G01X800282Y909891D02*
X760484Y724723D01*
G01X800282Y909891D02*
X760484Y724723D01*
G01X799044Y910319D02*
X759151Y724712D01*
G01X794252Y913683D02*
X753539Y724266D01*
G01X795490Y913255D02*
X754871Y724275D01*
G01X795490Y913255D02*
X754871Y724275D01*
G01X794252Y913683D02*
X753539Y724266D01*
G01X783995Y916431D02*
X769036Y848328D01*
G01X770255Y847817D02*
X785232Y916001D01*
G01X770255Y847817D02*
X785232Y916001D01*
G01X783995Y916431D02*
X769036Y848328D01*
G01X920524Y1183209D02*
X788205Y912286D01*
G01X789443Y911858D02*
X921539Y1182322D01*
G01X789443Y911858D02*
X921539Y1182322D01*
G01X920524Y1183209D02*
X788205Y912286D01*
G01X916438Y1188359D02*
X783995Y916431D01*
G01X785232Y916001D02*
X917453Y1187473D01*
G01X785232Y916001D02*
X917453Y1187473D01*
G01X916438Y1188359D02*
X783995Y916431D01*
G01X908673Y1148013D02*
X794252Y913683D01*
G01X909662Y1147075D02*
X795490Y913255D01*
G01X909662Y1147075D02*
X795490Y913255D01*
G01X908673Y1148013D02*
X794252Y913683D01*
G01X901978Y1199720D02*
X797222Y1038410D01*
G01X901978Y1199720D02*
X797222Y1038410D01*
G01X893347Y1201827D02*
X791916Y1045640D01*
G01X792832Y1044663D02*
X894292Y1200894D01*
G01X792832Y1044663D02*
X894292Y1200894D01*
G01X893347Y1201827D02*
X791916Y1045640D01*
G01X890272Y1206546D02*
X790150Y1052605D01*
G01X791066Y1051627D02*
X891216Y1205613D01*
G01X791066Y1051627D02*
X891216Y1205613D01*
G01X890272Y1206546D02*
X790150Y1052605D01*
G01X753034Y1094154D02*
X749451D01*
G01X753416Y1092854D02*
X749451D01*
G01X760988Y1099260D02*
X753034Y1094154D01*
G01X761897Y1098298D02*
X753416Y1092854D01*
G01X865994Y1244010D02*
X760988Y1099260D01*
G01X866910Y1243058D02*
X761897Y1098298D01*
G01X753416Y1092854D02*
X749451D01*
G01X753034Y1094154D02*
X749451D01*
G01X761897Y1098298D02*
X753416Y1092854D01*
G01X760988Y1099260D02*
X753034Y1094154D01*
G01X866910Y1243058D02*
X761897Y1098298D01*
G01X865994Y1244010D02*
X760988Y1099260D01*
G01X873789Y1269490D02*
X762051Y1244716D01*
G01X762556Y1243496D02*
X874294Y1268270D01*
G01X762556Y1243496D02*
X874294Y1268270D01*
G01X873789Y1269490D02*
X762051Y1244716D01*
G01X767875Y1250911D02*
X870362Y1273634D01*
G01X767875Y1250911D02*
X870362Y1273634D01*
G01X824952Y814877D02*
X845214Y732788D01*
G01X846554Y732786D02*
X826292Y814875D01*
G01X846554Y732786D02*
X826292Y814875D01*
G01X824952Y814877D02*
X845214Y732788D01*
G01X816825Y820659D02*
X838415Y726971D01*
G01X818163Y820645D02*
X839753Y726955D01*
G01X818163Y820645D02*
X839753Y726955D01*
G01X816825Y820659D02*
X838415Y726971D01*
G01X840336Y810305D02*
X856967Y742857D01*
G01X840336Y810305D02*
X856967Y742857D01*
G01X840336Y810305D02*
X856967Y742857D01*
G01X833439Y812475D02*
X851538Y739151D01*
G01X834779Y812473D02*
X852878Y739149D01*
G01X834779Y812473D02*
X852878Y739149D01*
G01X833439Y812475D02*
X851538Y739151D01*
G01X841676Y810302D02*
X849953Y776736D01*
G01X906612Y1074784D02*
X840336Y810305D01*
G01X849306Y840746D02*
X841676Y810303D01*
G01Y810302D02*
X849953Y776736D01*
G01X849306Y840746D02*
X841676Y810303D01*
G01X906612Y1074784D02*
X840336Y810305D01*
G01X906612Y1074784D02*
X840336Y810305D01*
G01X898046Y1070275D02*
X833439Y812475D01*
G01X867028Y941150D02*
X834779Y812473D01*
G01X867028Y941150D02*
X834779Y812473D01*
G01X898046Y1070275D02*
X833439Y812475D01*
G01X898046Y1070275D02*
X833439Y812475D01*
G01X887875Y1065959D02*
X824952Y814877D01*
G01X826292Y814875D02*
X857698Y940193D01*
G01X887875Y1065959D02*
X824952Y814877D01*
G01X826292Y814875D02*
X857698Y940193D01*
G01X887875Y1065959D02*
X824952Y814877D01*
G01X876076Y1055908D02*
X816825Y820659D01*
G01X877304Y1055459D02*
X818163Y820645D01*
G01X877304Y1055459D02*
X818163Y820645D01*
G01X876076Y1055908D02*
X816825Y820659D01*
G01X912422Y1142454D02*
X799044Y910319D01*
G01X913411Y1141516D02*
X800282Y909891D01*
G01X913411Y1141516D02*
X800282Y909891D01*
G01X912422Y1142454D02*
X799044Y910319D01*
G01X854289Y1112993D02*
X801133Y1031142D01*
G01X802049Y1030165D02*
X908389Y1193910D01*
G01X802049Y1030165D02*
X908389Y1193910D01*
G01X802049Y1030165D02*
X908389Y1193910D01*
G01X854289Y1112993D02*
X801133Y1031142D01*
G01X902923Y1198787D02*
X798138Y1037433D01*
G01X902923Y1198787D02*
X798138Y1037433D01*
G01X804796Y1246553D02*
X872341Y1261528D01*
G01X805301Y1245333D02*
X872846Y1260308D01*
G01X804602Y1246430D02*
X804796Y1246553D01*
G01X804603Y1246430D02*
X804602D01*
G01X805301Y1245333D02*
X872846Y1260308D01*
G01X804796Y1246553D02*
X872341Y1261528D01*
G01X804602Y1246430D02*
X804796Y1246553D01*
G01X804603Y1246430D02*
X804602D01*
G01X849953Y776736D02*
X858307Y742854D01*
G01X849953Y776736D02*
X858307Y742854D01*
G01X907840Y1074336D02*
X849306Y840746D01*
G01X907840Y1074336D02*
X849306Y840746D01*
G01X899274Y1069827D02*
X867028Y941150D01*
G01X899274Y1069827D02*
X867028Y941150D01*
G01X857698Y940193D02*
X889103Y1065511D01*
G01X857698Y940193D02*
X889103Y1065511D01*
G01X920730Y1133236D02*
X887875Y1065959D01*
G01X889103Y1065511D02*
X921720Y1132298D01*
G01X889103Y1065511D02*
X921720Y1132298D01*
G01X920730Y1133236D02*
X887875Y1065959D01*
G01X915909Y1137464D02*
X876076Y1055908D01*
G01X916898Y1136526D02*
X877304Y1055459D01*
G01X916898Y1136526D02*
X877304Y1055459D01*
G01X915909Y1137464D02*
X876076Y1055908D01*
G01X907444Y1194843D02*
X854289Y1112993D01*
G01X907444Y1194843D02*
X854289Y1112993D01*
G01X1040957Y1300466D02*
X893347Y1201827D01*
G01X894292Y1200894D02*
X1054300Y1307818D01*
G01X894292Y1200894D02*
X1054300Y1307818D01*
G01X894292Y1200894D02*
X1054300Y1307818D01*
G01X894292Y1200894D02*
X1054300Y1307818D01*
G01X894292Y1200894D02*
X1054300Y1307818D01*
G01X894292Y1200894D02*
X1054300Y1307818D01*
G01X894292Y1200894D02*
X1054300Y1307818D01*
G01X894292Y1200894D02*
X1054300Y1307818D01*
G01X1040957Y1300466D02*
X893347Y1201827D01*
G01X1039482Y1306255D02*
X890272Y1206546D01*
G01X891216Y1205613D02*
X1054021Y1314406D01*
G01X891216Y1205613D02*
X1054021Y1314406D01*
G01X891216Y1205613D02*
X1054021Y1314406D01*
G01X891216Y1205613D02*
X1054021Y1314406D01*
G01X891216Y1205613D02*
X1054021Y1314406D01*
G01X891216Y1205613D02*
X1054021Y1314406D01*
G01X891216Y1205613D02*
X1054021Y1314406D01*
G01X891216Y1205613D02*
X1054021Y1314406D01*
G01X1039482Y1306255D02*
X890272Y1206546D01*
G01X938760Y1292636D02*
X865994Y1244010D01*
G01X1012057Y1340050D02*
X866910Y1243058D01*
G01X1012057Y1340050D02*
X866910Y1243058D01*
G01X1012057Y1340050D02*
X866910Y1243058D01*
G01X938760Y1292636D02*
X865994Y1244010D01*
G01X872341Y1261528D02*
X1013256Y1351296D01*
G01X872846Y1260308D02*
X1013836Y1350123D01*
G01X872846Y1260308D02*
X1013836Y1350123D01*
G01X872341Y1261528D02*
X1013256Y1351296D01*
G01X1037223Y1373606D02*
X873789Y1269490D01*
G01X874294Y1268270D02*
X1037803Y1372433D01*
G01X874294Y1268270D02*
X1037803Y1372433D01*
G01X1037223Y1373606D02*
X873789Y1269490D01*
G01X869857Y1274854D02*
X1031765Y1378006D01*
G01X870362Y1273634D02*
X1032345Y1376833D01*
G01X870362Y1273634D02*
X1032345Y1376833D01*
G01X869857Y1274854D02*
X1031765Y1378006D01*
G01X1028544Y1383721D02*
X869360Y1282308D01*
G01X869865Y1281088D02*
X1029124Y1382548D01*
G01X869865Y1281088D02*
X1029124Y1382548D01*
G01X1028544Y1383721D02*
X869360Y1282308D01*
G01X1029474Y1391756D02*
X866532Y1287395D01*
G01X867039Y1286175D02*
X1030055Y1390584D01*
G01X867039Y1286175D02*
X1030055Y1390584D01*
G01X1029474Y1391756D02*
X866532Y1287395D01*
G01X926539Y1115593D02*
X906612Y1074784D01*
G01X927529Y1114655D02*
X907840Y1074336D01*
G01X927529Y1114655D02*
X907840Y1074336D01*
G01X926539Y1115593D02*
X906612Y1074784D01*
G01X921683Y1118682D02*
X898046Y1070275D01*
G01X922673Y1117744D02*
X899274Y1069827D01*
G01X922673Y1117744D02*
X899274Y1069827D01*
G01X921683Y1118682D02*
X898046Y1070275D01*
G01X1064810Y1192517D02*
X926539Y1115593D01*
G01X1078389Y1198583D02*
X927529Y1114655D01*
G01X1078389Y1198583D02*
X927529Y1114655D01*
G01X1078389Y1198583D02*
X927529Y1114655D01*
G01X1078389Y1198583D02*
X927529Y1114655D01*
G01X1078389Y1198583D02*
X927529Y1114655D01*
G01X1064810Y1192517D02*
X926539Y1115593D01*
G01X1061848Y1196666D02*
X921683Y1118682D01*
G01X1080706Y1205670D02*
X922673Y1117744D01*
G01X1080706Y1205670D02*
X922673Y1117744D01*
G01X1080706Y1205670D02*
X922673Y1117744D01*
G01X1080706Y1205670D02*
X922673Y1117744D01*
G01X1080706Y1205670D02*
X922673Y1117744D01*
G01X1061848Y1196666D02*
X921683Y1118682D01*
G01X1051639Y1206065D02*
X920730Y1133236D01*
G01X921720Y1132298D02*
X1066340Y1212756D01*
G01X921720Y1132298D02*
X1066340Y1212756D01*
G01X921720Y1132298D02*
X1066340Y1212756D01*
G01X921720Y1132298D02*
X1066340Y1212756D01*
G01X921720Y1132298D02*
X1066340Y1212756D01*
G01X1051639Y1206065D02*
X920730Y1133236D01*
G01X1051585Y1212939D02*
X915909Y1137464D01*
G01X965194Y1163392D02*
X916898Y1136526D01*
G01X965194Y1163392D02*
X916898Y1136526D01*
G01X1051585Y1212939D02*
X915909Y1137464D01*
G01X1051585Y1212939D02*
X915909Y1137464D01*
G01X1051585Y1212939D02*
X915909Y1137464D01*
G01X1051585Y1212939D02*
X915909Y1137464D01*
G01X950461Y1163614D02*
X912422Y1142454D01*
G01X932251Y1151996D02*
X913411Y1141516D01*
G01X951092Y1162477D02*
X932251Y1151996D01*
G01D02*
X913411Y1141516D01*
G01X950461Y1163614D02*
X912422Y1142454D01*
G01X951092Y1162477D02*
X932251Y1151996D01*
G01X950461Y1163614D02*
X912422Y1142454D01*
G01X950461Y1163614D02*
X912422Y1142454D01*
G01X947352Y1169524D02*
X908673Y1148013D01*
G01X967145Y1179043D02*
X909662Y1147075D01*
G01X967145Y1179043D02*
X909662Y1147075D01*
G01X947352Y1169524D02*
X908673Y1148013D01*
G01X1052625Y1271484D02*
X920524Y1183209D01*
G01X921539Y1182322D02*
X1053218Y1270316D01*
G01X921539Y1182322D02*
X1053218Y1270316D01*
G01X1052625Y1271484D02*
X920524Y1183209D01*
G01X1050584Y1278000D02*
X916438Y1188359D01*
G01X917453Y1187473D02*
X1051180Y1276834D01*
G01X917453Y1187473D02*
X1051180Y1276834D01*
G01X1050584Y1278000D02*
X916438Y1188359D01*
G01X1046540Y1287793D02*
X907444Y1194843D01*
G01X908389Y1193910D02*
X1058809Y1294428D01*
G01X908389Y1193910D02*
X1058809Y1294428D01*
G01X908389Y1193910D02*
X1058809Y1294428D01*
G01X908389Y1193910D02*
X1058809Y1294428D01*
G01X908389Y1193910D02*
X1058809Y1294428D01*
G01X908389Y1193910D02*
X1058809Y1294428D01*
G01X908389Y1193910D02*
X1058809Y1294428D01*
G01X908389Y1193910D02*
X1058809Y1294428D01*
G01X1046540Y1287793D02*
X907444Y1194843D01*
G01X1045155Y1295397D02*
X901978Y1199720D01*
G01X974401Y1246552D02*
X902923Y1198787D01*
G01X974401Y1246552D02*
X902923Y1198787D01*
G01X1045155Y1295397D02*
X901978Y1199720D01*
G01X1045155Y1295397D02*
X901978Y1199720D01*
G01X1011464Y1341218D02*
X938760Y1292636D01*
G01X1011464Y1341218D02*
X938760Y1292636D01*
G01X979663Y1171441D02*
X965194Y1163392D01*
G01X984558Y1174164D02*
X979663Y1171441D01*
G01X1066670Y1219843D02*
X984558Y1174164D01*
G01X1066670Y1219843D02*
X984558Y1174164D01*
G01X1066670Y1219843D02*
X984558Y1174164D01*
G01X1066670Y1219843D02*
X984558Y1174164D01*
G01X979663Y1171441D02*
X965194Y1163392D01*
G01X984558Y1174164D02*
X979663Y1171441D01*
G01X1066670Y1219843D02*
X984558Y1174164D01*
G01X951093Y1162477D02*
X951092D01*
G01X988145Y1184577D02*
X950461Y1163614D01*
G01X951093Y1162477D02*
X951092D01*
G01X1066958Y1226930D02*
X951093Y1162477D01*
G01X1066958Y1226930D02*
X951093Y1162477D01*
G01X1066958Y1226930D02*
X951093Y1162477D01*
G01X1066958Y1226930D02*
X951093Y1162477D01*
G01X1066958Y1226930D02*
X951093Y1162477D01*
G01D02*
X951092D01*
G01X988145Y1184577D02*
X950461Y1163614D01*
G01X1066958Y1226930D02*
X951093Y1162477D01*
G01X988145Y1184577D02*
X950461Y1163614D01*
G01X985674Y1190837D02*
X947352Y1169524D01*
G01X986306Y1189700D02*
X967145Y1179043D01*
G01X986306Y1189700D02*
X967145Y1179043D01*
G01X985674Y1190837D02*
X947352Y1169524D01*
G01X1049967Y1218967D02*
X988145Y1184577D01*
G01X1049967Y1218967D02*
X988145Y1184577D01*
G01X1000134Y1198879D02*
X985674Y1190837D01*
G01X1065992Y1234016D02*
X986306Y1189700D01*
G01X1065992Y1234016D02*
X986306Y1189700D01*
G01X1065992Y1234016D02*
X986306Y1189700D01*
G01X1065992Y1234016D02*
X986306Y1189700D01*
G01X1065992Y1234016D02*
X986306Y1189700D01*
G01X1065992Y1234016D02*
X986306Y1189700D01*
G01X1065992Y1234016D02*
X986306Y1189700D01*
G01X1065992Y1234016D02*
X986306Y1189700D01*
G01X1000134Y1198879D02*
X985674Y1190837D01*
G01X1055975Y1301063D02*
X974401Y1246552D01*
G01X1055975Y1301063D02*
X974401Y1246552D01*
G01X1055975Y1301063D02*
X974401Y1246552D01*
G01X1055975Y1301063D02*
X974401Y1246552D01*
G01X1055975Y1301063D02*
X974401Y1246552D01*
G01X1055975Y1301063D02*
X974401Y1246552D01*
G01X1055975Y1301063D02*
X974401Y1246552D01*
G01X1055975Y1301063D02*
X974401Y1246552D01*
G01X1004955Y1201560D02*
X1000134Y1198879D01*
G01X1024238Y1212284D02*
X1004955Y1201560D01*
G01X1047226Y1225068D02*
X1024238Y1212284D01*
G01X1004955Y1201560D02*
X1000134Y1198879D01*
G01X1024238Y1212284D02*
X1004955Y1201560D01*
G01X1047226Y1225068D02*
X1024238Y1212284D01*
G01X1056794Y1357799D02*
X1011464Y1341218D01*
G01X1090279Y1368662D02*
X1012057Y1340050D01*
G01X1090279Y1368662D02*
X1012057Y1340050D01*
G01X1090279Y1368662D02*
X1012057Y1340050D01*
G01X1090279Y1368662D02*
X1012057Y1340050D01*
G01X1090279Y1368662D02*
X1012057Y1340050D01*
G01X1056794Y1357799D02*
X1011464Y1341218D01*
G01X1013836Y1350123D02*
X1083899Y1375749D01*
G01X1013836Y1350123D02*
X1083899Y1375749D01*
G01X1013836Y1350123D02*
X1083899Y1375749D01*
G01X1032750Y1358426D02*
X1052110Y1365507D01*
G01X1013836Y1350123D02*
X1083899Y1375749D01*
G01X1013256Y1351296D02*
X1032750Y1358426D01*
G01X1013836Y1350123D02*
X1083899Y1375749D01*
G01X1013836Y1350123D02*
X1083899Y1375749D01*
G01X1032750Y1358426D02*
X1052110Y1365507D01*
G01X1013256Y1351296D02*
X1032750Y1358426D01*
G01X1037803Y1372433D02*
X1066245Y1382835D01*
G01X1037803Y1372433D02*
X1066245Y1382835D01*
G01X1037803Y1372433D02*
X1066245Y1382835D01*
G01X1037803Y1372433D02*
X1066245Y1382835D01*
G01X1037803Y1372433D02*
X1066245Y1382835D01*
G01X1050498Y1378461D02*
X1037223Y1373606D01*
G01X1050498Y1378461D02*
X1037223Y1373606D01*
G01X1032345Y1376833D02*
X1068131Y1389922D01*
G01X1032345Y1376833D02*
X1068131Y1389922D01*
G01X1032345Y1376833D02*
X1068131Y1389922D01*
G01X1031765Y1378006D02*
X1047601Y1383798D01*
G01X1032345Y1376833D02*
X1068131Y1389922D01*
G01X1032345Y1376833D02*
X1068131Y1389922D01*
G01X1031765Y1378006D02*
X1047601Y1383798D01*
G01X1043549Y1389209D02*
X1028544Y1383721D01*
G01X1029124Y1382548D02*
X1068658Y1397007D01*
G01X1029124Y1382548D02*
X1068658Y1397007D01*
G01X1029124Y1382548D02*
X1068658Y1397007D01*
G01X1029124Y1382548D02*
X1068658Y1397007D01*
G01X1029124Y1382548D02*
X1068658Y1397007D01*
G01X1043549Y1389209D02*
X1028544Y1383721D01*
G01X1039076Y1395268D02*
X1029474Y1391756D01*
G01X1037156Y1393181D02*
X1039523Y1394047D01*
G01X1030055Y1390584D02*
X1037156Y1393181D01*
G01D02*
X1039523Y1394047D01*
G01X1039076Y1395268D02*
X1029474Y1391756D01*
G01X1030055Y1390584D02*
X1037156Y1393181D01*
G01X1039076Y1395268D02*
X1029474Y1391756D01*
G01X1068393Y1194510D02*
X1067344Y1193927D01*
G01X1071976Y1196503D02*
X1070927Y1195920D01*
G01X1078051Y1199883D02*
X1074510Y1197913D01*
G01X1125233Y1199883D02*
X1078051D01*
G01X1125233Y1198583D02*
X1078389D01*
G01X1068393Y1194510D02*
X1067344Y1193927D01*
G01X1071976Y1196503D02*
X1070927Y1195920D01*
G01X1078051Y1199883D02*
X1074510Y1197913D01*
G01X1125233Y1198583D02*
X1078389D01*
G01X1125233Y1199883D02*
X1078051D01*
G01X1065431Y1198659D02*
X1064382Y1198076D01*
G01X1069013Y1200653D02*
X1067965Y1200069D01*
G01X1080368Y1206970D02*
X1071548Y1202063D01*
G01X1129170Y1206970D02*
X1080368D01*
G01X1129170Y1205670D02*
X1080706D01*
G01X1065431Y1198659D02*
X1064382Y1198076D01*
G01X1069013Y1200653D02*
X1067965Y1200069D01*
G01X1080368Y1206970D02*
X1071548Y1202063D01*
G01X1129170Y1205670D02*
X1080706D01*
G01X1129170Y1206970D02*
X1080368D01*
G01X1055222Y1208059D02*
X1054173Y1207475D01*
G01X1058805Y1210052D02*
X1057756Y1209468D01*
G01X1066002Y1214056D02*
X1061339Y1211462D01*
G01X1125233Y1214056D02*
X1066002D01*
G01X1066340Y1212756D02*
X1125233D01*
G01X1066340D02*
X1125233D01*
G01Y1214056D02*
X1066002D01*
G01X1055222Y1208059D02*
X1054173Y1207475D01*
G01X1058805Y1210052D02*
X1057756Y1209468D01*
G01X1066002Y1214056D02*
X1061339Y1211462D01*
G01X1055168Y1214933D02*
X1054119Y1214349D01*
G01X1058751Y1216926D02*
X1057702Y1216342D01*
G01X1066332Y1221143D02*
X1061285Y1218336D01*
G01X1129170Y1221143D02*
X1066332D01*
G01X1129170Y1219843D02*
X1066670D01*
G01X1055168Y1214933D02*
X1054119Y1214349D01*
G01X1058751Y1216926D02*
X1057702Y1216342D01*
G01X1066332Y1221143D02*
X1061285Y1218336D01*
G01X1129170Y1219843D02*
X1066670D01*
G01X1129170Y1221143D02*
X1066332D01*
G01X1053550Y1220960D02*
X1052502Y1220377D01*
G01X1057133Y1222953D02*
X1056085Y1222370D01*
G01X1066620Y1228230D02*
X1059668Y1224363D01*
G01X1125233Y1226930D02*
X1066958D01*
G01X1053550Y1220960D02*
X1052502Y1220377D01*
G01X1057133Y1222953D02*
X1056085Y1222370D01*
G01X1066620Y1228230D02*
X1059668Y1224363D01*
G01X1125233Y1226930D02*
X1066958D01*
G01X1050809Y1227061D02*
X1049760Y1226478D01*
G01X1050809Y1227061D02*
X1049760Y1226478D01*
G01X1053752Y1271896D02*
X1052625Y1271484D01*
G01X1053218Y1270316D02*
X1089598Y1283623D01*
G01X1057602Y1273305D02*
X1056476Y1272892D01*
G01X1053218Y1270316D02*
X1089598Y1283623D01*
G01X1061453Y1274713D02*
X1060326Y1274301D01*
G01X1053218Y1270316D02*
X1089598Y1283623D01*
G01X1089367Y1284923D02*
X1064177Y1275709D01*
G01X1053218Y1270316D02*
X1089598Y1283623D01*
G01X1053218Y1270316D02*
X1089598Y1283623D01*
G01X1053752Y1271896D02*
X1052625Y1271484D01*
G01X1057602Y1273305D02*
X1056476Y1272892D01*
G01X1061453Y1274713D02*
X1060326Y1274301D01*
G01X1089367Y1284923D02*
X1064177Y1275709D01*
G01X1125233Y1228230D02*
X1066620D01*
G01X1125233D02*
X1066620D01*
G01X1054392Y1229053D02*
X1053344Y1228470D01*
G01X1065654Y1235316D02*
X1056927Y1230463D01*
G01X1129170Y1235316D02*
X1065654D01*
G01X1129170Y1234016D02*
X1065992D01*
G01X1054392Y1229053D02*
X1053344Y1228470D01*
G01X1065654Y1235316D02*
X1056927Y1230463D01*
G01X1129170Y1234016D02*
X1065992D01*
G01X1129170Y1235316D02*
X1065654D01*
G01X1051982Y1278512D02*
X1050584Y1278001D01*
G01X1051180Y1276834D02*
X1089115Y1290709D01*
G01X1055832Y1279921D02*
X1054705Y1279508D01*
G01X1051180Y1276834D02*
X1089115Y1290709D01*
G01X1059683Y1281329D02*
X1058556Y1280917D01*
G01X1051180Y1276834D02*
X1089115Y1290709D01*
G01X1088884Y1292009D02*
X1062406Y1282325D01*
G01X1051180Y1276834D02*
X1089115Y1290709D01*
G01X1051180Y1276834D02*
X1089115Y1290709D01*
G01X1051982Y1278512D02*
X1050584Y1278001D01*
G01X1055832Y1279921D02*
X1054705Y1279508D01*
G01X1059683Y1281329D02*
X1058556Y1280917D01*
G01X1088884Y1292009D02*
X1062406Y1282325D01*
G01X1048951Y1289405D02*
X1047772Y1289639D01*
G01X1049949Y1290071D02*
X1048951Y1289405D01*
G01X1052360Y1291683D02*
X1051181Y1291917D01*
G01X1053358Y1292349D02*
X1052360Y1291683D01*
G01X1055769Y1293961D02*
X1054590Y1294195D01*
G01X1058216Y1295596D02*
X1055769Y1293961D01*
G01X1067790Y1299096D02*
X1058216Y1295596D01*
G01X1058809Y1294428D02*
X1068021Y1297796D01*
G01X1125233Y1299096D02*
X1067790D01*
G01X1068021Y1297796D02*
X1125233D01*
G01X1068021D02*
X1125233D01*
G01Y1299096D02*
X1067790D01*
G01X1058809Y1294428D02*
X1068021Y1297796D01*
G01X1067790Y1299096D02*
X1058216Y1295596D01*
G01X1048951Y1289405D02*
X1047772Y1289639D01*
G01X1049949Y1290071D02*
X1048951Y1289405D01*
G01X1052360Y1291683D02*
X1051181Y1291917D01*
G01X1053358Y1292349D02*
X1052360Y1291683D01*
G01X1055769Y1293961D02*
X1054590Y1294195D01*
G01X1058216Y1295596D02*
X1055769Y1293961D01*
G01X1047566Y1297008D02*
X1046387Y1297243D01*
G01X1048564Y1297675D02*
X1047566Y1297008D01*
G01X1050975Y1299286D02*
X1049796Y1299521D01*
G01X1051973Y1299953D02*
X1050975Y1299286D01*
G01X1054384Y1301564D02*
X1053205Y1301799D01*
G01X1055382Y1302231D02*
X1054384Y1301564D01*
G01X1066190Y1306182D02*
X1055382Y1302231D01*
G01X1066421Y1304882D02*
X1055975Y1301063D01*
G01X1129170Y1306182D02*
X1066190D01*
G01X1129170Y1304882D02*
X1066421D01*
G01X1047566Y1297008D02*
X1046387Y1297243D01*
G01X1048564Y1297675D02*
X1047566Y1297008D01*
G01X1050975Y1299286D02*
X1049796Y1299521D01*
G01X1051973Y1299953D02*
X1050975Y1299286D01*
G01X1054384Y1301564D02*
X1053205Y1301799D01*
G01X1055382Y1302231D02*
X1054384Y1301564D01*
G01X1066421Y1304882D02*
X1055975Y1301063D01*
G01X1066190Y1306182D02*
X1055382Y1302231D01*
G01X1129170Y1304882D02*
X1066421D01*
G01X1129170Y1306182D02*
X1066190D01*
G01X1043369Y1302078D02*
X1042190Y1302312D01*
G01X1044366Y1302744D02*
X1043369Y1302078D01*
G01X1046778Y1304356D02*
X1045599Y1304590D01*
G01X1047775Y1305022D02*
X1046778Y1304356D01*
G01X1050187Y1306634D02*
X1049008Y1306868D01*
G01X1053707Y1308986D02*
X1050187Y1306634D01*
G01X1065423Y1313269D02*
X1053707Y1308986D01*
G01X1054300Y1307818D02*
X1065654Y1311969D01*
G01X1125233Y1313269D02*
X1065423D01*
G01X1065654Y1311969D02*
X1125233D01*
G01X1065654D02*
X1125233D01*
G01Y1313269D02*
X1065423D01*
G01X1054300Y1307818D02*
X1065654Y1311969D01*
G01X1065423Y1313269D02*
X1053707Y1308986D01*
G01X1043369Y1302078D02*
X1042190Y1302312D01*
G01X1044366Y1302744D02*
X1043369Y1302078D01*
G01X1046778Y1304356D02*
X1045599Y1304590D01*
G01X1047775Y1305022D02*
X1046778Y1304356D01*
G01X1050187Y1306634D02*
X1049008Y1306868D01*
G01X1053707Y1308986D02*
X1050187Y1306634D01*
G01X1041893Y1307866D02*
X1040714Y1308100D01*
G01X1042891Y1308533D02*
X1041893Y1307866D01*
G01X1045302Y1310144D02*
X1044123Y1310378D01*
G01X1046300Y1310811D02*
X1045302Y1310144D01*
G01X1048711Y1312422D02*
X1047532Y1312656D01*
G01X1053428Y1315574D02*
X1048711Y1312422D01*
G01X1066509Y1320356D02*
X1053428Y1315574D01*
G01X1054021Y1314406D02*
X1066740Y1319056D01*
G01X1129170Y1320356D02*
X1066509D01*
G01X1066740Y1319056D02*
X1129170D01*
G01X1066740D02*
X1129170D01*
G01Y1320356D02*
X1066509D01*
G01X1054021Y1314406D02*
X1066740Y1319056D01*
G01X1066509Y1320356D02*
X1053428Y1315574D01*
G01X1041893Y1307866D02*
X1040714Y1308100D01*
G01X1042891Y1308533D02*
X1041893Y1307866D01*
G01X1045302Y1310144D02*
X1044123Y1310378D01*
G01X1046300Y1310811D02*
X1045302Y1310144D01*
G01X1048711Y1312422D02*
X1047532Y1312656D01*
G01X1053428Y1315574D02*
X1048711Y1312422D01*
G01X1060645Y1359207D02*
X1059518Y1358795D01*
G01X1064495Y1360616D02*
X1063368Y1360203D01*
G01X1090048Y1369962D02*
X1067219Y1361612D01*
G01X1060645Y1359207D02*
X1059518Y1358795D01*
G01X1064495Y1360616D02*
X1063368Y1360203D01*
G01X1090048Y1369962D02*
X1067219Y1361612D01*
G01X1062535Y1369320D02*
X1083668Y1377049D01*
G01X1058684Y1367911D02*
X1059811Y1368323D01*
G01X1054834Y1366503D02*
X1055961Y1366915D01*
G01X1062535Y1369320D02*
X1083668Y1377049D01*
G01X1058684Y1367911D02*
X1059811Y1368323D01*
G01X1054834Y1366503D02*
X1055961Y1366915D01*
G01X1083668Y1377049D02*
X1129170D01*
G01X1083899Y1375749D02*
X1129170D01*
G01X1083899D02*
X1129170D01*
G01X1083668Y1377049D02*
X1129170D01*
G01X1054349Y1379869D02*
X1053222Y1379457D01*
G01X1058200Y1381277D02*
X1057073Y1380865D01*
G01X1066014Y1384135D02*
X1060923Y1382273D01*
G01X1125233Y1384135D02*
X1066014D01*
G01X1066245Y1382835D02*
X1125233D01*
G01X1066245D02*
X1125233D01*
G01Y1384135D02*
X1066014D01*
G01X1054349Y1379869D02*
X1053222Y1379457D01*
G01X1058200Y1381277D02*
X1057073Y1380865D01*
G01X1066014Y1384135D02*
X1060923Y1382273D01*
G01X1067900Y1391222D02*
X1129170D01*
G01X1068131Y1389922D02*
X1129170D01*
G01X1058025Y1387610D02*
X1067900Y1391222D01*
G01X1054175Y1386202D02*
X1055302Y1386614D01*
G01X1050324Y1384794D02*
X1051451Y1385206D01*
G01X1068131Y1389922D02*
X1129170D01*
G01X1067900Y1391222D02*
X1129170D01*
G01X1058025Y1387610D02*
X1067900Y1391222D01*
G01X1054175Y1386202D02*
X1055302Y1386614D01*
G01X1050324Y1384794D02*
X1051451Y1385206D01*
G01X1047399Y1390617D02*
X1046273Y1390205D01*
G01X1051250Y1392026D02*
X1050123Y1391613D01*
G01X1068428Y1398308D02*
X1053974Y1393022D01*
G01X1125233Y1398308D02*
X1068428D01*
G01X1068659Y1397008D02*
X1125233D01*
G01X1068659D02*
X1125233D01*
G01Y1398308D02*
X1068428D01*
G01X1047399Y1390617D02*
X1046273Y1390205D01*
G01X1051250Y1392026D02*
X1050123Y1391613D01*
G01X1068428Y1398308D02*
X1053974Y1393022D01*
G01X1042926Y1396677D02*
X1041799Y1396264D01*
G01X1039523Y1394047D02*
X1049442Y1397674D01*
G01X1046777Y1398085D02*
X1045650Y1397673D01*
G01X1039523Y1394047D02*
X1049442Y1397674D01*
G01X1066764Y1405395D02*
X1049501Y1399081D01*
G01X1049442Y1397675D02*
X1066995Y1404095D01*
G01X1128683Y1405395D02*
X1066764D01*
G01X1066995Y1404095D02*
X1128683D01*
G01X1066995D02*
X1128683D01*
G01Y1405395D02*
X1066764D01*
G01X1049442Y1397675D02*
X1066995Y1404095D01*
G01X1066764Y1405395D02*
X1049501Y1399081D01*
G01X1039523Y1394047D02*
X1049442Y1397674D01*
G01X1042926Y1396677D02*
X1041799Y1396264D01*
G01X1046777Y1398085D02*
X1045650Y1397673D01*
G01X1102772Y1165098D02*
Y1166843D01*
G01X1101472Y1165098D02*
Y1166843D01*
G01X1103420Y1164450D02*
G02X1102772Y1165098I0J648D01*
G01X1103420Y1163150D02*
G02X1101472Y1165098I0J1948D01*
G01X1133949Y1164450D02*
X1103420D01*
G01X1133741Y1163150D02*
X1103420D01*
G01X1138747Y1162882D02*
X1133949Y1164450D01*
G01X1138145Y1161711D02*
X1133741Y1163150D01*
G01X1101472Y1165098D02*
Y1166843D01*
G01X1102772Y1165098D02*
Y1166843D01*
G01X1103420Y1163150D02*
G02X1101472Y1165098I0J1948D01*
G01X1103420Y1164450D02*
G02X1102772Y1165098I0J648D01*
G01X1133741Y1163150D02*
X1103420D01*
G01X1133949Y1164450D02*
X1103420D01*
G01X1138145Y1161711D02*
X1133741Y1163150D01*
G01X1138747Y1162882D02*
X1133949Y1164450D01*
G01X1135368Y1143340D02*
X1137179Y1142009D01*
G01X1134941Y1142040D02*
X1136409Y1140961D01*
G01X1134940Y1142040D02*
X1134941D01*
G01X1135367Y1143340D02*
X1135368D01*
G01X1129461Y1146065D02*
X1134940Y1142040D01*
G01X1130063Y1147237D02*
X1135367Y1143340D01*
G01X1129461Y1146065D02*
X1134940Y1142040D01*
G01X1124288Y1149120D02*
X1130063Y1147237D01*
G01X1099161Y1155944D02*
X1129461Y1146065D01*
G01X1120389Y1150391D02*
X1121530Y1150019D01*
G01X1099161Y1155944D02*
X1129461Y1146065D01*
G01X1116491Y1151662D02*
X1117632Y1151290D01*
G01X1099161Y1155944D02*
X1129461Y1146065D01*
G01X1099861Y1157084D02*
X1113734Y1152561D01*
G01X1099161Y1155944D02*
X1129461Y1146065D01*
G01X1098826Y1158119D02*
X1099861Y1157084D01*
G01X1097526Y1157580D02*
X1099161Y1155944D01*
G01X1098826Y1159857D02*
Y1158119D01*
G01X1097526Y1159857D02*
Y1157580D01*
G01X1134941Y1142040D02*
X1136409Y1140961D01*
G01X1135368Y1143340D02*
X1137179Y1142009D01*
G01X1134940Y1142040D02*
X1134941D01*
G01X1135368Y1143340D02*
X1137179Y1142009D01*
G01X1129461Y1146065D02*
X1134940Y1142040D01*
G01X1135367Y1143340D02*
X1135368D01*
G01X1130063Y1147237D02*
X1135367Y1143340D01*
G01X1099161Y1155944D02*
X1129461Y1146065D01*
G01X1124288Y1149120D02*
X1130063Y1147237D01*
G01X1120389Y1150391D02*
X1121530Y1150019D01*
G01X1116491Y1151662D02*
X1117632Y1151290D01*
G01X1099861Y1157084D02*
X1113734Y1152561D01*
G01X1097526Y1157580D02*
X1099161Y1155944D01*
G01X1098826Y1158119D02*
X1099861Y1157084D01*
G01X1097526Y1159857D02*
Y1157580D01*
G01X1098826Y1159857D02*
Y1158119D01*
G01X1129800Y1169588D02*
Y1167843D01*
G01X1131100Y1169588D02*
Y1167843D01*
G01X1131748Y1171536D02*
G03X1129800Y1169588I0J-1948D01*
G01X1131748Y1170236D02*
G03X1131100Y1169588I0J-648D01*
G01X1136282Y1171536D02*
X1131748D01*
G01X1136074Y1170236D02*
X1131748D01*
G01X1139100Y1169247D02*
X1136074Y1170236D01*
G01X1131100Y1169588D02*
Y1167843D01*
G01X1129800Y1169588D02*
Y1167843D01*
G01X1131748Y1170236D02*
G03X1131100Y1169588I0J-648D01*
G01X1131748Y1171536D02*
G03X1129800Y1169588I0J-1948D01*
G01X1136074Y1170236D02*
X1131748D01*
G01X1136282Y1171536D02*
X1131748D01*
G01X1139100Y1169247D02*
X1136074Y1170236D01*
G01X1127168Y1155992D02*
X1179193Y1117764D01*
G01X1135042Y1151821D02*
X1136230Y1152003D01*
G01X1134075Y1152532D02*
X1135042Y1151821D01*
G01X1131738Y1154249D02*
X1132926Y1154430D01*
G01X1128018Y1156982D02*
X1131738Y1154249D01*
G01X1126398Y1156762D02*
X1127168Y1155992D01*
G01X1127664Y1157336D02*
X1128018Y1156982D01*
G01X1127317Y1157682D02*
X1127664Y1157336D01*
G01X1125881Y1158012D02*
G03X1126395Y1156764I1767J-2D01*
G01X1127181Y1158012D02*
G03X1127317Y1157682I466J-1D01*
G01X1125881Y1159757D02*
Y1158012D01*
G01X1127181Y1159757D02*
Y1158012D01*
G01X1127168Y1155992D02*
X1179193Y1117764D01*
G01X1127168Y1155992D02*
X1179193Y1117764D01*
G01X1127168Y1155992D02*
X1179193Y1117764D01*
G01X1135042Y1151821D02*
X1136230Y1152003D01*
G01X1127168Y1155992D02*
X1179193Y1117764D01*
G01X1134075Y1152532D02*
X1135042Y1151821D01*
G01X1127168Y1155992D02*
X1179193Y1117764D01*
G01X1131738Y1154249D02*
X1132926Y1154430D01*
G01X1127168Y1155992D02*
X1179193Y1117764D01*
G01X1128018Y1156982D02*
X1131738Y1154249D01*
G01X1127168Y1155992D02*
X1179193Y1117764D01*
G01X1127664Y1157336D02*
X1128018Y1156982D01*
G01X1126398Y1156762D02*
X1127168Y1155992D01*
G01X1127317Y1157682D02*
X1127664Y1157336D01*
G01X1126398Y1156762D02*
X1127168Y1155992D01*
G01X1127181Y1158012D02*
G03X1127317Y1157682I466J-1D01*
G01X1125881Y1158012D02*
G03X1126395Y1156764I1767J-2D01*
G01X1127181Y1159757D02*
Y1158012D01*
G01X1125881Y1159757D02*
Y1158012D01*
G01Y1200531D02*
G02X1125233Y1199883I-648J0D01*
G01X1127181Y1200531D02*
G02X1125233Y1198583I-1948J0D01*
G01X1125881Y1202276D02*
Y1200531D01*
G01X1127181Y1202276D02*
Y1200531D01*
G01D02*
G02X1125233Y1198583I-1948J0D01*
G01X1125881Y1200531D02*
G02X1125233Y1199883I-648J0D01*
G01X1127181Y1202276D02*
Y1200531D01*
G01X1125881Y1202276D02*
Y1200531D01*
G01X1129818Y1207618D02*
G02X1129170Y1206970I-648J0D01*
G01X1131118Y1207618D02*
G02X1129170Y1205670I-1948J0D01*
G01X1129818Y1209363D02*
Y1207618D01*
G01X1131118Y1209363D02*
Y1207618D01*
G01D02*
G02X1129170Y1205670I-1948J0D01*
G01X1129818Y1207618D02*
G02X1129170Y1206970I-648J0D01*
G01X1131118Y1209363D02*
Y1207618D01*
G01X1129818Y1209363D02*
Y1207618D01*
G01X1125881Y1214704D02*
G02X1125233Y1214056I-648J0D01*
G01Y1212756D02*
G03X1127181Y1214704I0J1948D01*
G01X1125881Y1216449D02*
Y1214704D01*
G01X1127181D02*
Y1216449D01*
G01Y1214704D02*
Y1216449D01*
G01X1125881D02*
Y1214704D01*
G01X1125233Y1212756D02*
G03X1127181Y1214704I0J1948D01*
G01X1125881D02*
G02X1125233Y1214056I-648J0D01*
G01X1129818Y1221791D02*
G02X1129170Y1221143I-648J0D01*
G01X1131118Y1221791D02*
G02X1129170Y1219843I-1948J0D01*
G01X1129818Y1223536D02*
Y1221791D01*
G01X1131118Y1223536D02*
Y1221791D01*
G01D02*
G02X1129170Y1219843I-1948J0D01*
G01X1129818Y1221791D02*
G02X1129170Y1221143I-648J0D01*
G01X1131118Y1223536D02*
Y1221791D01*
G01X1129818Y1223536D02*
Y1221791D01*
G01X1127181Y1228878D02*
G02X1125233Y1226930I-1948J0D01*
G01X1127181Y1228878D02*
G02X1125233Y1226930I-1948J0D01*
G01X1125881Y1228878D02*
G02X1125233Y1228230I-648J0D01*
G01X1125881Y1230623D02*
Y1228878D01*
G01X1127181Y1230623D02*
Y1228878D01*
G01X1125881D02*
G02X1125233Y1228230I-648J0D01*
G01X1127181Y1230623D02*
Y1228878D01*
G01X1125881Y1230623D02*
Y1228878D01*
G01X1129818Y1235964D02*
G02X1129170Y1235316I-648J0D01*
G01X1131118Y1235964D02*
G02X1129170Y1234016I-1948J0D01*
G01X1129818Y1237709D02*
Y1235964D01*
G01X1131118Y1237709D02*
Y1235964D01*
G01D02*
G02X1129170Y1234016I-1948J0D01*
G01X1129818Y1235964D02*
G02X1129170Y1235316I-648J0D01*
G01X1131118Y1237709D02*
Y1235964D01*
G01X1129818Y1237709D02*
Y1235964D01*
G01X1125233Y1284923D02*
X1089367D01*
G01X1089598Y1283623D02*
X1125233D01*
G01X1125881Y1285571D02*
G02X1125233Y1284923I-648J0D01*
G01Y1283623D02*
G03X1127181Y1285571I0J1948D01*
G01X1125881Y1287316D02*
Y1285571D01*
G01X1127181D02*
Y1287316D01*
G01Y1285571D02*
Y1287316D01*
G01X1125881D02*
Y1285571D01*
G01X1125233Y1283623D02*
G03X1127181Y1285571I0J1948D01*
G01X1125881D02*
G02X1125233Y1284923I-648J0D01*
G01X1089598Y1283623D02*
X1125233D01*
G01Y1284923D02*
X1089367D01*
G01X1129170Y1292009D02*
X1088884D01*
G01X1089115Y1290709D02*
X1129170D01*
G01X1129818Y1292657D02*
G02X1129170Y1292009I-648J0D01*
G01Y1290709D02*
G03X1131118Y1292657I0J1948D01*
G01X1129818Y1294402D02*
Y1292657D01*
G01X1131118D02*
Y1294402D01*
G01Y1292657D02*
Y1294402D01*
G01X1129818D02*
Y1292657D01*
G01X1129170Y1290709D02*
G03X1131118Y1292657I0J1948D01*
G01X1129818D02*
G02X1129170Y1292009I-648J0D01*
G01X1089115Y1290709D02*
X1129170D01*
G01Y1292009D02*
X1088884D01*
G01X1125881Y1299744D02*
G02X1125233Y1299096I-648J0D01*
G01Y1297796D02*
G03X1127181Y1299744I0J1948D01*
G01X1125881Y1301489D02*
Y1299744D01*
G01X1127181D02*
Y1301489D01*
G01Y1299744D02*
Y1301489D01*
G01X1125881D02*
Y1299744D01*
G01X1125233Y1297796D02*
G03X1127181Y1299744I0J1948D01*
G01X1125881D02*
G02X1125233Y1299096I-648J0D01*
G01X1129818Y1306830D02*
G02X1129170Y1306182I-648J0D01*
G01X1131118Y1306830D02*
G02X1129170Y1304882I-1948J0D01*
G01X1129818Y1308575D02*
Y1306830D01*
G01X1131118Y1308575D02*
Y1306830D01*
G01D02*
G02X1129170Y1304882I-1948J0D01*
G01X1129818Y1306830D02*
G02X1129170Y1306182I-648J0D01*
G01X1131118Y1308575D02*
Y1306830D01*
G01X1129818Y1308575D02*
Y1306830D01*
G01X1125881Y1313917D02*
G02X1125233Y1313269I-648J0D01*
G01Y1311969D02*
G03X1127181Y1313917I0J1948D01*
G01X1125881Y1315662D02*
Y1313917D01*
G01X1127181D02*
Y1315662D01*
G01Y1313917D02*
Y1315662D01*
G01X1125881D02*
Y1313917D01*
G01X1125233Y1311969D02*
G03X1127181Y1313917I0J1948D01*
G01X1125881D02*
G02X1125233Y1313269I-648J0D01*
G01X1129818Y1321004D02*
G02X1129170Y1320356I-648J0D01*
G01Y1319056D02*
G03X1131118Y1321004I0J1948D01*
G01X1129818Y1322749D02*
Y1321004D01*
G01X1131118D02*
Y1322749D01*
G01Y1321004D02*
Y1322749D01*
G01X1129818D02*
Y1321004D01*
G01X1129170Y1319056D02*
G03X1131118Y1321004I0J1948D01*
G01X1129818D02*
G02X1129170Y1320356I-648J0D01*
G01X1125233Y1369962D02*
X1090048D01*
G01X1125233Y1368662D02*
X1090279D01*
G01X1125881Y1370610D02*
G02X1125233Y1369962I-648J0D01*
G01X1127181Y1370610D02*
G02X1125233Y1368662I-1948J0D01*
G01X1125881Y1372355D02*
Y1370610D01*
G01X1127181Y1372355D02*
Y1370610D01*
G01X1125233Y1368662D02*
X1090279D01*
G01X1125233Y1369962D02*
X1090048D01*
G01X1127181Y1370610D02*
G02X1125233Y1368662I-1948J0D01*
G01X1125881Y1370610D02*
G02X1125233Y1369962I-648J0D01*
G01X1127181Y1372355D02*
Y1370610D01*
G01X1125881Y1372355D02*
Y1370610D01*
G01X1129818Y1377697D02*
Y1379442D01*
G01X1131118Y1377697D02*
Y1379442D01*
G01X1129170Y1377049D02*
G03X1129818Y1377697I0J648D01*
G01X1129170Y1375749D02*
G03X1131118Y1377697I0J1948D01*
G01D02*
Y1379442D01*
G01X1129818Y1377697D02*
Y1379442D01*
G01X1129170Y1375749D02*
G03X1131118Y1377697I0J1948D01*
G01X1129170Y1377049D02*
G03X1129818Y1377697I0J648D01*
G01X1125881Y1384783D02*
G02X1125233Y1384135I-648J0D01*
G01Y1382835D02*
G03X1127181Y1384783I0J1948D01*
G01X1125881Y1386528D02*
Y1384783D01*
G01X1127181D02*
Y1386528D01*
G01Y1384783D02*
Y1386528D01*
G01X1125881D02*
Y1384783D01*
G01X1125233Y1382835D02*
G03X1127181Y1384783I0J1948D01*
G01X1125881D02*
G02X1125233Y1384135I-648J0D01*
G01X1129818Y1391870D02*
Y1393615D01*
G01X1131118Y1391870D02*
Y1393615D01*
G01X1129170Y1391222D02*
G03X1129818Y1391870I0J648D01*
G01X1129170Y1389922D02*
G03X1131118Y1391870I0J1948D01*
G01D02*
Y1393615D01*
G01X1129818Y1391870D02*
Y1393615D01*
G01X1129170Y1389922D02*
G03X1131118Y1391870I0J1948D01*
G01X1129170Y1391222D02*
G03X1129818Y1391870I0J648D01*
G01X1125881Y1398956D02*
G02X1125233Y1398308I-648J0D01*
G01Y1397008D02*
G03X1127181Y1398956I0J1948D01*
G01X1125881Y1400701D02*
Y1398956D01*
G01X1127181D02*
Y1400701D01*
G01Y1398956D02*
Y1400701D01*
G01X1125881D02*
Y1398956D01*
G01X1125233Y1397008D02*
G03X1127181Y1398956I0J1948D01*
G01X1125881D02*
G02X1125233Y1398308I-648J0D01*
G01X1129818Y1406530D02*
G02X1128683Y1405395I-1135J0D01*
G01Y1404095D02*
G03X1131118Y1406530I0J2435D01*
G01X1129818Y1407788D02*
Y1406530D01*
G01X1131118D02*
Y1407788D01*
G01Y1406530D02*
Y1407788D01*
G01X1129818D02*
Y1406530D01*
G01X1128683Y1404095D02*
G03X1131118Y1406530I0J2435D01*
G01X1129818D02*
G02X1128683Y1405395I-1135J0D01*
G01X1180805Y1130370D02*
X1138145Y1161711D01*
G01X1180805Y1130370D02*
X1138145Y1161711D01*
G01X1180805Y1130370D02*
X1138145Y1161711D01*
G01X1180805Y1130370D02*
X1138145Y1161711D01*
G01X1180805Y1130370D02*
X1138145Y1161711D01*
G01X1180805Y1130370D02*
X1138145Y1161711D01*
G01X1180805Y1130370D02*
X1138145Y1161711D01*
G01X1264167Y1024294D02*
X1181723Y1131309D01*
G01X1263101Y1023546D02*
X1180805Y1130370D01*
G01D02*
X1138145Y1161711D01*
G01X1263101Y1023546D02*
X1180805Y1130370D01*
G01X1264167Y1024294D02*
X1181723Y1131309D01*
G01X1171812Y1116566D02*
X1229797Y1039567D01*
G01X1170888Y1115631D02*
X1228590Y1039008D01*
G01X1138355Y1141145D02*
X1171812Y1116566D01*
G01X1137585Y1140097D02*
X1170888Y1115631D01*
G01D02*
X1228590Y1039008D01*
G01X1171812Y1116566D02*
X1229797Y1039567D01*
G01X1137585Y1140097D02*
X1170888Y1115631D01*
G01X1138355Y1141145D02*
X1171812Y1116566D01*
G01X1179193Y1117764D02*
X1243757Y1032028D01*
G01X1180117Y1118699D02*
X1244964Y1032587D01*
G01X1140682Y1147676D02*
X1180117Y1118699D01*
G01D02*
X1244964Y1032587D01*
G01X1179193Y1117764D02*
X1243757Y1032028D01*
G01X1140682Y1147676D02*
X1180117Y1118699D01*
G01X1157986Y1148748D02*
X1138747Y1162882D01*
G01X1159174Y1148930D02*
X1157986Y1148748D01*
G01X1161290Y1146321D02*
X1160323Y1147031D01*
G01X1162478Y1146503D02*
X1161290Y1146321D01*
G01X1164594Y1143893D02*
X1163627Y1144604D01*
G01X1165782Y1144075D02*
X1164594Y1143893D01*
G01X1181723Y1131309D02*
X1166931Y1142176D01*
G01X1157986Y1148748D02*
X1138747Y1162882D01*
G01X1159174Y1148930D02*
X1157986Y1148748D01*
G01X1161290Y1146321D02*
X1160323Y1147031D01*
G01X1162478Y1146503D02*
X1161290Y1146321D01*
G01X1164594Y1143893D02*
X1163627Y1144604D01*
G01X1165782Y1144075D02*
X1164594Y1143893D01*
G01X1181723Y1131309D02*
X1166931Y1142176D01*
G01X1137179Y1142009D02*
X1138355Y1141145D01*
G01X1136409Y1140961D02*
X1137585Y1140097D01*
G01X1136409Y1140961D02*
X1137585Y1140097D01*
G01X1137179Y1142009D02*
X1138355Y1141145D01*
G01X1139702Y1170418D02*
X1136282Y1171536D01*
G01X1187068Y1135618D02*
X1139702Y1170418D01*
G01X1148908Y1162041D02*
X1139100Y1169247D01*
G01X1151245Y1160324D02*
X1150057Y1160142D01*
G01X1152212Y1159613D02*
X1151245Y1160324D01*
G01X1154549Y1157896D02*
X1153361Y1157714D01*
G01X1155516Y1157186D02*
X1154549Y1157896D01*
G01X1157853Y1155469D02*
X1156665Y1155287D01*
G01X1186150Y1134679D02*
X1157853Y1155469D01*
G01X1139702Y1170418D02*
X1136282Y1171536D01*
G01X1148908Y1162041D02*
X1139100Y1169247D01*
G01X1187068Y1135618D02*
X1139702Y1170418D01*
G01X1151245Y1160324D02*
X1150057Y1160142D01*
G01X1187068Y1135618D02*
X1139702Y1170418D01*
G01X1152212Y1159613D02*
X1151245Y1160324D01*
G01X1187068Y1135618D02*
X1139702Y1170418D01*
G01X1154549Y1157896D02*
X1153361Y1157714D01*
G01X1187068Y1135618D02*
X1139702Y1170418D01*
G01X1155516Y1157186D02*
X1154549Y1157896D01*
G01X1187068Y1135618D02*
X1139702Y1170418D01*
G01X1157853Y1155469D02*
X1156665Y1155287D01*
G01X1187068Y1135618D02*
X1139702Y1170418D01*
G01X1186150Y1134679D02*
X1157853Y1155469D01*
G01X1187068Y1135618D02*
X1139702Y1170418D01*
G01X1138346Y1149393D02*
X1139534Y1149575D01*
G01X1137379Y1150104D02*
X1138346Y1149393D01*
G01D02*
X1139534Y1149575D01*
G01X1137379Y1150104D02*
X1138346Y1149393D01*
G01X1197734Y450217D02*
X1259650Y174968D01*
G01X1196404Y450202D02*
X1258350Y174823D01*
G01X1196404Y450202D02*
X1258350Y174823D01*
G01X1197734Y450217D02*
X1259650Y174968D01*
G01X1209916Y462395D02*
X1272000Y187793D01*
G01X1211246Y462411D02*
X1273300Y187939D01*
G01X1211246Y462411D02*
X1273300Y187939D01*
G01X1209916Y462395D02*
X1272000Y187793D01*
G01X1215281Y537525D02*
X1197734Y450217D01*
G01X1219837Y566793D02*
X1196404Y450202D01*
G01X1219837Y566793D02*
X1196404Y450202D01*
G01X1219837Y566793D02*
X1196404Y450202D01*
G01X1215281Y537525D02*
X1197734Y450217D01*
G01X1229748Y561088D02*
X1209916Y462395D01*
G01X1231076Y561095D02*
X1211246Y462411D01*
G01X1231076Y561095D02*
X1211246Y462411D01*
G01X1229748Y561088D02*
X1209916Y462395D01*
G01X1221165Y566800D02*
X1215281Y537525D01*
G01X1221165Y566800D02*
X1215281Y537525D01*
G01X1202040Y656817D02*
X1221165Y566800D01*
G01X1200712Y656810D02*
X1219837Y566793D01*
G01X1200712Y656810D02*
X1219837Y566793D01*
G01X1202040Y656817D02*
X1221165Y566800D01*
G01X1209539Y656192D02*
X1229748Y561088D01*
G01X1210867Y656199D02*
X1231076Y561095D01*
G01X1210867Y656199D02*
X1231076Y561095D01*
G01X1209539Y656192D02*
X1229748Y561088D01*
G01X1255787Y924289D02*
X1202040Y656817D01*
G01X1254457Y924273D02*
X1200712Y656810D01*
G01X1254457Y924273D02*
X1200712Y656810D01*
G01X1255787Y924289D02*
X1202040Y656817D01*
G01X1251578Y865425D02*
X1209539Y656192D01*
G01X1266921Y935187D02*
X1210867Y656199D01*
G01X1266921Y935187D02*
X1210867Y656199D01*
G01X1266921Y935187D02*
X1210867Y656199D01*
G01X1251578Y865425D02*
X1209539Y656192D01*
G01X1229797Y1039567D02*
X1255787Y924289D01*
G01X1228590Y1039008D02*
X1254457Y924273D01*
G01X1228590Y1039008D02*
X1254457Y924273D01*
G01X1229797Y1039567D02*
X1255787Y924289D01*
G01X1269301Y1028879D02*
X1187068Y1135618D01*
G01X1268236Y1028131D02*
X1186150Y1134679D01*
G01X1268236Y1028131D02*
X1186150Y1134679D01*
G01X1269301Y1028879D02*
X1187068Y1135618D01*
G01X1259650Y174968D02*
Y168223D01*
G01X1258350Y174823D02*
Y168223D01*
G01Y174823D02*
Y168223D01*
G01X1259650Y174968D02*
Y168223D01*
G01X1272000Y187793D02*
Y183223D01*
G01X1273300Y187939D02*
Y183223D01*
G01Y187939D02*
Y183223D01*
G01X1272000Y187793D02*
Y183223D01*
G01X1265591Y935171D02*
X1251578Y865426D01*
G01X1265591Y935171D02*
X1251578Y865426D01*
G01X1243757Y1032028D02*
X1265591Y935171D01*
G01X1244964Y1032587D02*
X1266921Y935187D01*
G01X1244964Y1032587D02*
X1266921Y935187D01*
G01X1243757Y1032028D02*
X1265591Y935171D01*
G01X1314462Y945347D02*
X1264167Y1024294D01*
G01X1313243Y944840D02*
X1263101Y1023546D01*
G01X1313243Y944840D02*
X1263101Y1023546D01*
G01X1314462Y945347D02*
X1264167Y1024294D01*
G01X1320958Y947861D02*
X1269301Y1028879D01*
G01X1319739Y947353D02*
X1268236Y1028131D01*
G01X1319739Y947353D02*
X1268236Y1028131D01*
G01X1320958Y947861D02*
X1269301Y1028879D01*
G01X1373075Y201700D02*
X1312759Y523031D01*
G01X1371823Y201318D02*
X1311434Y523039D01*
G01X1371823Y201318D02*
X1311434Y523039D01*
G01X1373075Y201700D02*
X1312759Y523031D01*
G01X1374866Y235177D02*
X1319489Y523364D01*
G01X1373616Y234792D02*
X1318164Y523369D01*
G01X1373616Y234792D02*
X1318164Y523369D01*
G01X1374866Y235177D02*
X1319489Y523364D01*
G01X1312759Y523031D02*
X1358410Y750211D01*
G01X1311434Y523039D02*
X1357080Y750196D01*
G01X1311434Y523039D02*
X1357080Y750196D01*
G01X1312759Y523031D02*
X1358410Y750211D01*
G01X1319489Y523364D02*
X1365288Y751233D01*
G01X1318164Y523369D02*
X1363957Y751219D01*
G01X1318164Y523369D02*
X1363957Y751219D01*
G01X1319489Y523364D02*
X1365288Y751233D01*
G01X1358410Y750211D02*
X1314462Y945347D01*
G01X1335160Y847519D02*
X1313243Y944840D01*
G01X1335160Y847519D02*
X1313243Y944840D01*
G01X1358410Y750211D02*
X1314462Y945347D01*
G01X1358410Y750211D02*
X1314462Y945347D01*
G01X1365288Y751233D02*
X1320958Y947861D01*
G01X1363957Y751219D02*
X1319739Y947353D01*
G01X1363957Y751219D02*
X1319739Y947353D01*
G01X1365288Y751233D02*
X1320958Y947861D01*
G01X1383863Y176691D02*
X1373075Y201700D01*
G01X1381219Y179536D02*
X1371823Y201318D01*
G01X1381219Y179536D02*
X1371823Y201318D01*
G01X1383863Y176691D02*
X1373075Y201700D01*
G01X1383863Y176691D02*
X1373075Y201700D01*
G01X1391685Y196192D02*
X1374866Y235177D01*
G01X1390532Y195581D02*
X1373616Y234792D01*
G01X1390532Y195581D02*
X1373616Y234792D01*
G01X1391685Y196192D02*
X1374866Y235177D01*
G01X1357080Y750196D02*
X1335161Y847519D01*
G01X1357080Y750196D02*
X1335161Y847519D01*
G01X1382562Y176422D02*
X1381219Y179536D01*
G01X1383863Y168223D02*
Y176691D01*
G01X1382563Y168223D02*
Y176422D01*
G01X1382562D02*
X1381219Y179536D01*
G01X1382563Y168223D02*
Y176422D01*
G01X1383863Y168223D02*
Y176691D01*
G01X1394685Y191484D02*
X1391685Y196192D01*
G01X1393743Y190542D02*
X1390532Y195581D01*
G01X1398544Y189024D02*
X1394685Y191484D01*
G01X1398038Y187804D02*
X1393743Y190542D01*
G01X1400264Y188642D02*
X1398544Y189025D01*
G01X1400121Y187342D02*
X1398038Y187804D01*
G01X1402313Y188642D02*
X1400264D01*
G01X1402313Y187342D02*
X1400121D01*
G01X1393743Y190542D02*
X1390532Y195581D01*
G01X1394685Y191484D02*
X1391685Y196192D01*
G01X1398038Y187804D02*
X1393743Y190542D01*
G01X1398544Y189024D02*
X1394685Y191484D01*
G01X1400121Y187342D02*
X1398038Y187804D01*
G01X1400264Y188642D02*
X1398544Y189025D01*
G01X1402313Y187342D02*
X1400121D01*
G01X1402313Y188642D02*
X1400264D01*
G54D12*
G01X485506Y123024D02*
X508314Y138128D01*
G01X486300Y122230D02*
X508747Y137095D01*
G01X482911Y119104D02*
X485506Y123024D01*
G01X483767Y118404D02*
X486300Y122230D01*
G01X481928Y118121D02*
X482911Y119104D01*
G01X482384Y117021D02*
X483767Y118404D01*
G01X479831Y118121D02*
X481928D01*
G01X479832Y117021D02*
X482384D01*
G01X486300Y122230D02*
X508747Y137095D01*
G01X485506Y123024D02*
X508314Y138128D01*
G01X483767Y118404D02*
X486300Y122230D01*
G01X482911Y119104D02*
X485506Y123024D01*
G01X482384Y117021D02*
X483767Y118404D01*
G01X481928Y118121D02*
X482911Y119104D01*
G01X479832Y117021D02*
X482384D01*
G01X479831Y118121D02*
X481928D01*
G01X508314Y138128D02*
X559235Y148949D01*
G01X508747Y137095D02*
X559235Y147824D01*
G01X508747Y137095D02*
X559235Y147824D01*
G01X508314Y138128D02*
X559235Y148949D01*
G01X589710Y142472D02*
X660221Y96683D01*
G01X589282Y141438D02*
X659762Y95669D01*
G01X559235Y148949D02*
X589710Y142472D01*
G01X559235Y147824D02*
X589282Y141438D01*
G01D02*
X659762Y95669D01*
G01X589710Y142472D02*
X660221Y96683D01*
G01X559235Y147824D02*
X589282Y141438D01*
G01X559235Y148949D02*
X589710Y142472D01*
G01X660221Y96683D02*
X732672Y76323D01*
G01X659762Y95669D02*
X732635Y75190D01*
G01X659762Y95669D02*
X732635Y75190D01*
G01X660221Y96683D02*
X732672Y76323D01*
G01D02*
X803333Y91342D01*
G01X732635Y75190D02*
X768231Y82756D01*
G01X732672Y76323D02*
X803333Y91342D01*
G01X732635Y75190D02*
X768231Y82756D01*
G01X732672Y76323D02*
X803333Y91342D01*
G01X768231Y82755D02*
X803333Y90217D01*
G01X768231Y82755D02*
X803333Y90217D01*
G01Y91342D02*
X874719Y76168D01*
G01X803333Y90217D02*
X874291Y75134D01*
G01X803333Y90217D02*
X874291Y75134D01*
G01X803333Y91342D02*
X874719Y76168D01*
G01X874291Y75134D02*
X920907Y44862D01*
G01X874291Y75134D02*
X920907Y44862D01*
G01X874291Y75134D02*
X920907Y44862D01*
G01X874719Y76168D02*
X908686Y54111D01*
G01X874291Y75134D02*
X920907Y44862D01*
G01X874291Y75134D02*
X920907Y44862D01*
G01X874719Y76168D02*
X908686Y54111D01*
G01X884927Y555125D02*
X921949Y498116D01*
G01X883890Y554701D02*
X902515Y526022D01*
G01X884927Y555125D02*
X921949Y498116D01*
G01X884927Y555125D02*
X921949Y498116D01*
G01X883890Y554701D02*
X902515Y526022D01*
G01X878775Y548399D02*
X922849Y480530D01*
G01X879812Y548823D02*
X901723Y515082D01*
G01X851770Y681087D02*
X878775Y548399D01*
G01X852899Y681058D02*
X879812Y548823D01*
G01X878775Y548399D02*
X922849Y480530D01*
G01X879812Y548823D02*
X901723Y515082D01*
G01X878775Y548399D02*
X922849Y480530D01*
G01X852899Y681058D02*
X879812Y548823D01*
G01X851770Y681087D02*
X878775Y548399D01*
G01X874061Y541130D02*
X924192Y463969D01*
G01X875098Y541555D02*
X924979Y464779D01*
G01X846258Y677666D02*
X874061Y541130D01*
G01X847387Y677638D02*
X875098Y541555D01*
G01D02*
X924979Y464779D01*
G01X874061Y541130D02*
X924192Y463969D01*
G01X847387Y677638D02*
X875098Y541555D01*
G01X846258Y677666D02*
X874061Y541130D01*
G01X889609Y558242D02*
X917509Y515277D01*
G01X890646Y558666D02*
X918296Y516087D01*
G01X876651Y621893D02*
X889609Y558242D01*
G01X877780Y621864D02*
X890646Y558666D01*
G01D02*
X918296Y516087D01*
G01X889609Y558242D02*
X917509Y515277D01*
G01X877780Y621864D02*
X890646Y558666D01*
G01X876651Y621893D02*
X889609Y558242D01*
G01X870496Y620646D02*
X883890Y554701D01*
G01X871625Y620617D02*
X884927Y555125D01*
G01X871625Y620617D02*
X884927Y555125D01*
G01X870496Y620646D02*
X883890Y554701D01*
G01X921735Y797409D02*
X876651Y621893D01*
G01X922760Y796977D02*
X877780Y621864D01*
G01X922760Y796977D02*
X877780Y621864D01*
G01X921735Y797409D02*
X876651Y621893D01*
G01X910517Y776497D02*
X870496Y620646D01*
G01X911583Y776223D02*
X871625Y620617D01*
G01X911583Y776223D02*
X871625Y620617D01*
G01X910517Y776497D02*
X870496Y620646D01*
G01X926560Y793674D02*
X894486Y668780D01*
G01X926560Y793674D02*
X894486Y668780D01*
G01X926560Y793674D02*
X894486Y668780D01*
G01X861600Y719368D02*
X851770Y681087D01*
G01X862625Y718936D02*
X852899Y681058D01*
G01X862625Y718936D02*
X852899Y681058D01*
G01X861600Y719368D02*
X851770Y681087D01*
G01X858539Y725520D02*
X846258Y677666D01*
G01X859564Y725088D02*
X847387Y677638D01*
G01X859564Y725088D02*
X847387Y677638D01*
G01X858539Y725520D02*
X846258Y677666D01*
G01X1028340Y993484D02*
X861600Y719368D01*
G01X972119Y898940D02*
X862625Y718936D01*
G01X972119Y898940D02*
X862625Y718936D01*
G01X1028340Y993484D02*
X861600Y719368D01*
G01X1028340Y993484D02*
X861600Y719368D01*
G01X1028340Y993484D02*
X861600Y719368D01*
G01X1028340Y993484D02*
X861600Y719368D01*
G01X1028340Y993484D02*
X861600Y719368D01*
G01X1028340Y993484D02*
X861600Y719368D01*
G01X1028340Y993484D02*
X861600Y719368D01*
G01X1028340Y993484D02*
X861600Y719368D01*
G01X1028340Y993484D02*
X861600Y719368D01*
G01X1028340Y993484D02*
X861600Y719368D01*
G01X1028340Y993484D02*
X861600Y719368D01*
G01X1028340Y993484D02*
X861600Y719368D01*
G01X999909Y957958D02*
X858539Y725520D01*
G01X1000613Y956996D02*
X859564Y725088D01*
G01X1000613Y956996D02*
X859564Y725088D01*
G01X999909Y957958D02*
X858539Y725520D01*
G01X931579Y44895D02*
X932429Y45745D01*
G01X932357Y44117D02*
X933654Y45414D01*
G01X930990Y44651D02*
G03X931579Y44895I0J832D01*
G01X930991Y43551D02*
G03X932357Y44117I0J1932D01*
G01X927188Y44651D02*
X930990D01*
G01X927072Y43551D02*
X930991D01*
G01X921335Y45896D02*
X927188Y44651D01*
G01X920907Y44862D02*
X927072Y43551D01*
G01X917743Y48229D02*
X921335Y45896D01*
G01X914305Y50462D02*
X915563Y49645D01*
G01X910866Y52695D02*
X912124Y51878D01*
G01X932357Y44117D02*
X933654Y45414D01*
G01X931579Y44895D02*
X932429Y45745D01*
G01X930991Y43551D02*
G03X932357Y44117I0J1932D01*
G01X930990Y44651D02*
G03X931579Y44895I0J832D01*
G01X927072Y43551D02*
X930991D01*
G01X927188Y44651D02*
X930990D01*
G01X920907Y44862D02*
X927072Y43551D01*
G01X921335Y45896D02*
X927188Y44651D01*
G01X917743Y48229D02*
X921335Y45896D01*
G01X914305Y50462D02*
X915563Y49645D01*
G01X910866Y52695D02*
X912124Y51878D01*
G01X932415Y494174D02*
X933654Y495413D01*
G01X931637Y494952D02*
X932429Y495744D01*
G01X930893Y493544D02*
G03X932415Y494174I1J2152D01*
G01X930893Y494644D02*
G03X931637Y494952I0J1052D01*
G01X927343Y493544D02*
X930893D01*
G01X927652Y494644D02*
X930893D01*
G01X921162Y497306D02*
X927343Y493544D01*
G01X921949Y498116D02*
X927652Y494644D01*
G01X902515Y526022D02*
X921162Y497306D01*
G01X931637Y494952D02*
X932429Y495744D01*
G01X932415Y494174D02*
X933654Y495413D01*
G01X930893Y494644D02*
G03X931637Y494952I0J1052D01*
G01X930893Y493544D02*
G03X932415Y494174I1J2152D01*
G01X927652Y494644D02*
X930893D01*
G01X927343Y493544D02*
X930893D01*
G01X921949Y498116D02*
X927652Y494644D01*
G01X921162Y497306D02*
X927343Y493544D01*
G01X902515Y526022D02*
X921162Y497306D01*
G01X932450Y478461D02*
X933654Y479665D01*
G01X931672Y479239D02*
X932429Y479996D01*
G01X930845Y477796D02*
G03X932450Y478461I-1J2271D01*
G01X930844Y478896D02*
G03X931672Y479239I0J1171D01*
G01X927342Y477796D02*
X930845D01*
G01X927651Y478896D02*
X930844D01*
G01X922849Y480530D02*
X927342Y477796D01*
G01X923636Y481340D02*
X927651Y478896D01*
G01X901723Y515082D02*
X923636Y481340D01*
G01X931672Y479239D02*
X932429Y479996D01*
G01X932450Y478461D02*
X933654Y479665D01*
G01X930844Y478896D02*
G03X931672Y479239I0J1171D01*
G01X930845Y477796D02*
G03X932450Y478461I-1J2271D01*
G01X927651Y478896D02*
X930844D01*
G01X927342Y477796D02*
X930845D01*
G01X923636Y481340D02*
X927651Y478896D01*
G01X922849Y480530D02*
X927342Y477796D01*
G01X901723Y515082D02*
X923636Y481340D01*
G01X932394Y462657D02*
X933654Y463917D01*
G01X931616Y463435D02*
X932429Y464248D01*
G01X930923Y462048D02*
G03X932394Y462657I0J2080D01*
G01X930923Y463148D02*
G03X931616Y463435I0J980D01*
G01X927344Y462048D02*
X930923D01*
G01X927653Y463148D02*
X930923D01*
G01X925743Y463024D02*
X927344Y462048D01*
G01X924979Y464779D02*
X927653Y463148D01*
G01X924192Y463969D02*
X925743Y463024D01*
G01X924979Y464779D02*
X927653Y463148D01*
G01X931616Y463435D02*
X932429Y464248D01*
G01X932394Y462657D02*
X933654Y463917D01*
G01X930923Y463148D02*
G03X931616Y463435I0J980D01*
G01X930923Y462048D02*
G03X932394Y462657I0J2080D01*
G01X927653Y463148D02*
X930923D01*
G01X927344Y462048D02*
X930923D01*
G01X924979Y464779D02*
X927653Y463148D01*
G01X925743Y463024D02*
X927344Y462048D01*
G01X924192Y463969D02*
X925743Y463024D01*
G01X932336Y509843D02*
X933654Y511161D01*
G01X931558Y510621D02*
X932429Y511492D01*
G01X931005Y509292D02*
G03X932336Y509843I0J1882D01*
G01X931005Y510392D02*
G03X931558Y510621I0J782D01*
G01X927341Y509292D02*
X931005D01*
G01X927650Y510392D02*
X931005D01*
G01X917509Y515277D02*
X927341Y509292D01*
G01X918296Y516087D02*
X927650Y510392D01*
G01X931558Y510621D02*
X932429Y511492D01*
G01X932336Y509843D02*
X933654Y511161D01*
G01X931005Y510392D02*
G03X931558Y510621I0J782D01*
G01X931005Y509292D02*
G03X932336Y509843I0J1882D01*
G01X927650Y510392D02*
X931005D01*
G01X927341Y509292D02*
X931005D01*
G01X918296Y516087D02*
X927650Y510392D01*
G01X917509Y515277D02*
X927341Y509292D01*
G01X932399Y588646D02*
X933654Y589901D01*
G01X931621Y589424D02*
X932429Y590232D01*
G01X930916Y588032D02*
G03X932399Y588646I0J2097D01*
G01X930916Y589132D02*
G03X931621Y589424I0J997D01*
G01X928180Y588032D02*
X930916D01*
G01X928489Y589132D02*
X930916D01*
G01X908482Y600026D02*
X928180Y588032D01*
G01X909465Y600716D02*
X928489Y589132D01*
G01X931621Y589424D02*
X932429Y590232D01*
G01X932399Y588646D02*
X933654Y589901D01*
G01X930916Y589132D02*
G03X931621Y589424I0J997D01*
G01X930916Y588032D02*
G03X932399Y588646I0J2097D01*
G01X928489Y589132D02*
X930916D01*
G01X928180Y588032D02*
X930916D01*
G01X909465Y600716D02*
X928489Y589132D01*
G01X908482Y600026D02*
X928180Y588032D01*
G01X932444Y635935D02*
X933654Y637145D01*
G01X931666Y636713D02*
X932429Y637476D01*
G01X930857Y635278D02*
G03X932444Y635935I0J2244D01*
G01X930857Y636378D02*
G03X931666Y636713I0J1144D01*
G01X927339Y635278D02*
X930857D01*
G01X927990Y636378D02*
X930857D01*
G01X927648Y636379D02*
X927990D01*
G01X924504Y637005D02*
X927339Y635279D01*
G01X927648Y636379D02*
X927990D01*
G01X925487Y637695D02*
X927648Y636379D01*
G01X919589Y661144D02*
X924504Y637004D01*
G01X920667Y661363D02*
X925487Y637695D01*
G01X931666Y636713D02*
X932429Y637476D01*
G01X932444Y635935D02*
X933654Y637145D01*
G01X930857Y636378D02*
G03X931666Y636713I0J1144D01*
G01X930857Y635278D02*
G03X932444Y635935I0J2244D01*
G01X927990Y636378D02*
X930857D01*
G01X927339Y635278D02*
X930857D01*
G01X927648Y636379D02*
X927990D01*
G01X927339Y635278D02*
X930857D01*
G01X924504Y637005D02*
X927339Y635279D01*
G01X925487Y637695D02*
X927648Y636379D01*
G01X924504Y637005D02*
X927339Y635279D01*
G01X920667Y661363D02*
X925487Y637695D01*
G01X919589Y661144D02*
X924504Y637004D01*
G01X919589Y661144D02*
X924504Y637004D01*
G01X932432Y620175D02*
X933654Y621397D01*
G01X931654Y620953D02*
X932429Y621728D01*
G01X930869Y619528D02*
G03X932432Y620175I1J2210D01*
G01X930869Y620628D02*
G03X931654Y620953I0J1110D01*
G01X927342Y619528D02*
X930869D01*
G01X927651Y620628D02*
X930869D01*
G01X919064Y624562D02*
X927342Y619528D01*
G01X920047Y625253D02*
X927651Y620628D01*
G01X908131Y678242D02*
X919064Y624562D01*
G01X909231Y678353D02*
X920047Y625253D01*
G01X931654Y620953D02*
X932429Y621728D01*
G01X932432Y620175D02*
X933654Y621397D01*
G01X930869Y620628D02*
G03X931654Y620953I0J1110D01*
G01X930869Y619528D02*
G03X932432Y620175I1J2210D01*
G01X927651Y620628D02*
X930869D01*
G01X927342Y619528D02*
X930869D01*
G01X920047Y625253D02*
X927651Y620628D01*
G01X919064Y624562D02*
X927342Y619528D01*
G01X909231Y678353D02*
X920047Y625253D01*
G01X908131Y678242D02*
X919064Y624562D01*
G01X932404Y604399D02*
X933654Y605649D01*
G01X931626Y605177D02*
X932429Y605980D01*
G01X930910Y603780D02*
G03X932404Y604399I-1J2114D01*
G01X930909Y604880D02*
G03X931626Y605177I0J1014D01*
G01X927414Y603780D02*
X930910D01*
G01X927707Y604880D02*
X930909D01*
G01X912907Y612078D02*
X927414Y603780D01*
G01X913886Y612786D02*
X927707Y604880D01*
G01X900850Y671288D02*
X912907Y612078D01*
G01X902019Y671061D02*
X913886Y612786D01*
G01X931626Y605177D02*
X932429Y605980D01*
G01X932404Y604399D02*
X933654Y605649D01*
G01X930909Y604880D02*
G03X931626Y605177I0J1014D01*
G01X930910Y603780D02*
G03X932404Y604399I-1J2114D01*
G01X927707Y604880D02*
X930909D01*
G01X927414Y603780D02*
X930910D01*
G01X913886Y612786D02*
X927707Y604880D01*
G01X912907Y612078D02*
X927414Y603780D01*
G01X902019Y671061D02*
X913886Y612786D01*
G01X900850Y671288D02*
X912907Y612078D01*
G01X894486Y668780D02*
X908482Y600026D01*
G01X895615Y668751D02*
X909465Y600716D01*
G01X895615Y668751D02*
X909465Y600716D01*
G01X894486Y668780D02*
X908482Y600026D01*
G01X920601Y661688D02*
X920667Y661364D01*
G01X915119Y683092D02*
X919588Y661145D01*
G01X920601Y661688D02*
X920667Y661364D01*
G01X916288Y682865D02*
X920600Y661689D01*
G01X933977Y756158D02*
X915273Y683325D01*
G01X935002Y755726D02*
X916293Y682872D01*
G01X920601Y661688D02*
X920667Y661364D01*
G01X915119Y683092D02*
X919588Y661145D01*
G01X916288Y682865D02*
X920600Y661689D01*
G01X915119Y683092D02*
X919588Y661145D01*
G01X935002Y755726D02*
X916293Y682872D01*
G01X933977Y756158D02*
X915273Y683325D01*
G01X908131Y678501D02*
Y678242D01*
G01X909231Y678362D02*
Y678353D01*
G01X928689Y758549D02*
X908131Y678501D01*
G01X929789Y758410D02*
X909231Y678362D01*
G01D02*
Y678353D01*
G01X908131Y678501D02*
Y678242D01*
G01X929789Y758410D02*
X909231Y678362D01*
G01X928689Y758549D02*
X908131Y678501D01*
G01X914952Y725825D02*
X901000Y671515D01*
G01X916018Y725551D02*
X902020Y671062D01*
G01X916018Y725551D02*
X902020Y671062D01*
G01X914952Y725825D02*
X901000Y671515D01*
G01X911601Y730997D02*
X895615Y668751D01*
G01X911601Y730997D02*
X895615Y668751D01*
G01X928991Y780474D02*
X914952Y725825D01*
G01X930016Y780042D02*
X916018Y725551D01*
G01X930016Y780042D02*
X916018Y725551D01*
G01X928991Y780474D02*
X914952Y725825D01*
G01X927585Y793242D02*
X911601Y730997D01*
G01X927585Y793242D02*
X911601Y730997D01*
G01X1069032Y978216D02*
X933977Y756158D01*
G01X1022880Y900215D02*
X935002Y755726D01*
G01X1022880Y900215D02*
X935002Y755726D01*
G01X1069032Y978216D02*
X933977Y756158D01*
G01X1069032Y978216D02*
X933977Y756158D01*
G01X1069032Y978216D02*
X933977Y756158D01*
G01X1069032Y978216D02*
X933977Y756158D01*
G01X1069032Y978216D02*
X933977Y756158D01*
G01X1069032Y978216D02*
X933977Y756158D01*
G01X1069032Y978216D02*
X933977Y756158D01*
G01X1069032Y978216D02*
X933977Y756158D01*
G01X1069032Y978216D02*
X933977Y756158D01*
G01X1069032Y978216D02*
X933977Y756158D01*
G01X1069032Y978216D02*
X933977Y756158D01*
G01X1069032Y978216D02*
X933977Y756158D01*
G01X931663Y770129D02*
X928689Y758554D01*
G01X932688Y769697D02*
X929790Y758410D01*
G01X1058178Y978146D02*
X931663Y770129D01*
G01X1013610Y902748D02*
X932688Y769697D01*
G01D02*
X929790Y758410D01*
G01X931663Y770129D02*
X928689Y758554D01*
G01X1013610Y902748D02*
X932688Y769697D01*
G01X1058178Y978146D02*
X931663Y770129D01*
G01X1058178Y978146D02*
X931663Y770129D01*
G01X1058178Y978146D02*
X931663Y770129D01*
G01X1058178Y978146D02*
X931663Y770129D01*
G01X1058178Y978146D02*
X931663Y770129D01*
G01X1058178Y978146D02*
X931663Y770129D01*
G01X1058178Y978146D02*
X931663Y770129D01*
G01X1058178Y978146D02*
X931663Y770129D01*
G01X1058178Y978146D02*
X931663Y770129D01*
G01X1058178Y978146D02*
X931663Y770129D01*
G01X1058178Y978146D02*
X931663Y770129D01*
G01X1058178Y978146D02*
X931663Y770129D01*
G01X1050500Y980262D02*
X928991Y780474D01*
G01X1022022Y931319D02*
X930016Y780042D01*
G01X1022022Y931319D02*
X930016Y780042D01*
G01X1050500Y980262D02*
X928991Y780474D01*
G01X1050500Y980262D02*
X928991Y780474D01*
G01X1050500Y980262D02*
X928991Y780474D01*
G01X1050500Y980262D02*
X928991Y780474D01*
G01X1050500Y980262D02*
X928991Y780474D01*
G01X1050500Y980262D02*
X928991Y780474D01*
G01X1050500Y980262D02*
X928991Y780474D01*
G01X1050500Y980262D02*
X928991Y780474D01*
G01X1050500Y980262D02*
X928991Y780474D01*
G01X916407Y799434D02*
X910517Y776497D01*
G01X917432Y799002D02*
X911583Y776223D01*
G01X917432Y799002D02*
X911583Y776223D01*
G01X916407Y799434D02*
X910517Y776497D01*
G01X1039889Y980017D02*
X926560Y793674D01*
G01X1002556Y916514D02*
X927585Y793242D01*
G01X1002556Y916514D02*
X927585Y793242D01*
G01X1039889Y980017D02*
X926560Y793674D01*
G01X1039889Y980017D02*
X926560Y793674D01*
G01X1039889Y980017D02*
X926560Y793674D01*
G01X1039889Y980017D02*
X926560Y793674D01*
G01X1039889Y980017D02*
X926560Y793674D01*
G01X1039889Y980017D02*
X926560Y793674D01*
G01X1039889Y980017D02*
X926560Y793674D01*
G01X1039889Y980017D02*
X926560Y793674D01*
G01X1034667Y983099D02*
X921735Y797409D01*
G01X996289Y917878D02*
X922760Y796977D01*
G01X996289Y917878D02*
X922760Y796977D01*
G01X1034667Y983099D02*
X921735Y797409D01*
G01X1034667Y983099D02*
X921735Y797409D01*
G01X1034667Y983099D02*
X921735Y797409D01*
G01X1034667Y983099D02*
X921735Y797409D01*
G01X1034667Y983099D02*
X921735Y797409D01*
G01X1034667Y983099D02*
X921735Y797409D01*
G01X1034667Y983099D02*
X921735Y797409D01*
G01X1034667Y983099D02*
X921735Y797409D01*
G01X1030651Y987298D02*
X916407Y799434D01*
G01X992877Y923063D02*
X917432Y799002D01*
G01X992877Y923063D02*
X917432Y799002D01*
G01X1030651Y987298D02*
X916407Y799434D01*
G01X1030651Y987298D02*
X916407Y799434D01*
G01X1030651Y987298D02*
X916407Y799434D01*
G01X1030651Y987298D02*
X916407Y799434D01*
G01X1030651Y987298D02*
X916407Y799434D01*
G01X1030651Y987298D02*
X916407Y799434D01*
G01X1030651Y987298D02*
X916407Y799434D01*
G01X1030651Y987298D02*
X916407Y799434D01*
G01X950103Y488719D02*
X950267Y488392D01*
G01X951138Y489109D02*
X951230Y488928D01*
G01X951087Y489212D02*
X951138Y489109D01*
G01X950513Y490354D02*
X951087Y489212D01*
G01X949586Y489746D02*
X950102Y488720D01*
G01X951087Y489212D02*
X951138Y489109D01*
G01X950513Y490354D02*
X951087Y489212D01*
G01X949735Y491854D02*
G03X949586Y489746I1139J-1140D01*
G01X950513Y491076D02*
G03Y490354I361J-361D01*
G01X952525Y494644D02*
X949735Y491854D01*
G01X952981Y493544D02*
X950513Y491076D01*
G01X956015Y494644D02*
X952525D01*
G01X956318Y493544D02*
X952981D01*
G01X959415Y496668D02*
X956015Y494644D01*
G01X960170Y495836D02*
X956318Y493544D01*
G01X997357Y548252D02*
X959415Y496668D01*
G01X998387Y547794D02*
X960170Y495836D01*
G01X951138Y489109D02*
X951230Y488928D01*
G01X950103Y488719D02*
X950267Y488392D01*
G01X951087Y489212D02*
X951138Y489109D01*
G01X950103Y488719D02*
X950267Y488392D01*
G01X949586Y489746D02*
X950102Y488720D01*
G01X950513Y490354D02*
X951087Y489212D01*
G01X950103Y488719D02*
X950267Y488392D01*
G01X949586Y489746D02*
X950102Y488720D01*
G01X950513Y491076D02*
G03Y490354I361J-361D01*
G01X949735Y491854D02*
G03X949586Y489746I1139J-1140D01*
G01X952981Y493544D02*
X950513Y491076D01*
G01X952525Y494644D02*
X949735Y491854D01*
G01X956318Y493544D02*
X952981D01*
G01X956015Y494644D02*
X952525D01*
G01X960170Y495836D02*
X956318Y493544D01*
G01X959415Y496668D02*
X956015Y494644D01*
G01X998387Y547794D02*
X960170Y495836D01*
G01X997357Y548252D02*
X959415Y496668D01*
G01X950103Y472971D02*
X950267Y472644D01*
G01X951138Y473361D02*
X951230Y473180D01*
G01X951087Y473464D02*
X951138Y473361D01*
G01X950513Y474606D02*
X951087Y473464D01*
G01X949586Y473998D02*
X950102Y472972D01*
G01X951087Y473464D02*
X951138Y473361D01*
G01X950513Y474606D02*
X951087Y473464D01*
G01X949735Y476106D02*
G03X949586Y473998I1139J-1140D01*
G01X950513Y475328D02*
G03Y474606I361J-361D01*
G01X952525Y478896D02*
X949735Y476106D01*
G01X952981Y477796D02*
X950513Y475328D01*
G01X956109Y478896D02*
X952525D01*
G01X956387Y477796D02*
X952981D01*
G01X959123Y480522D02*
X956109Y478896D01*
G01X959863Y479671D02*
X956387Y477796D01*
G01X1002590Y539619D02*
X959123Y480522D01*
G01X1003620Y539162D02*
X959863Y479671D01*
G01X951138Y473361D02*
X951230Y473180D01*
G01X950103Y472971D02*
X950267Y472644D01*
G01X951087Y473464D02*
X951138Y473361D01*
G01X950103Y472971D02*
X950267Y472644D01*
G01X949586Y473998D02*
X950102Y472972D01*
G01X950513Y474606D02*
X951087Y473464D01*
G01X950103Y472971D02*
X950267Y472644D01*
G01X949586Y473998D02*
X950102Y472972D01*
G01X950513Y475328D02*
G03Y474606I361J-361D01*
G01X949735Y476106D02*
G03X949586Y473998I1139J-1140D01*
G01X952981Y477796D02*
X950513Y475328D01*
G01X952525Y478896D02*
X949735Y476106D01*
G01X956387Y477796D02*
X952981D01*
G01X956109Y478896D02*
X952525D01*
G01X959863Y479671D02*
X956387Y477796D01*
G01X959123Y480522D02*
X956109Y478896D01*
G01X1003620Y539162D02*
X959863Y479671D01*
G01X1002590Y539619D02*
X959123Y480522D01*
G01X950103Y457223D02*
X950267Y456896D01*
G01X951138Y457613D02*
X951230Y457432D01*
G01X951087Y457716D02*
X951138Y457613D01*
G01X950513Y458858D02*
X951087Y457716D01*
G01X949586Y458250D02*
X950102Y457224D01*
G01X951087Y457716D02*
X951138Y457613D01*
G01X950513Y458858D02*
X951087Y457716D01*
G01X949735Y460358D02*
G03X949586Y458250I1139J-1140D01*
G01X950513Y459580D02*
G03Y458858I361J-361D01*
G01X952525Y463148D02*
X949735Y460358D01*
G01X952981Y462048D02*
X950513Y459580D01*
G01X955905Y463148D02*
X952525D01*
G01X956177Y462048D02*
X952981D01*
G01X959202Y464883D02*
X955905Y463148D01*
G01X959938Y464027D02*
X956177Y462048D01*
G01X1007798Y530952D02*
X959202Y464883D01*
G01X1008828Y530495D02*
X959938Y464027D01*
G01X951138Y457613D02*
X951230Y457432D01*
G01X950103Y457223D02*
X950267Y456896D01*
G01X951087Y457716D02*
X951138Y457613D01*
G01X950103Y457223D02*
X950267Y456896D01*
G01X949586Y458250D02*
X950102Y457224D01*
G01X950513Y458858D02*
X951087Y457716D01*
G01X950103Y457223D02*
X950267Y456896D01*
G01X949586Y458250D02*
X950102Y457224D01*
G01X950513Y459580D02*
G03Y458858I361J-361D01*
G01X949735Y460358D02*
G03X949586Y458250I1139J-1140D01*
G01X952981Y462048D02*
X950513Y459580D01*
G01X952525Y463148D02*
X949735Y460358D01*
G01X956177Y462048D02*
X952981D01*
G01X955905Y463148D02*
X952525D01*
G01X959938Y464027D02*
X956177Y462048D01*
G01X959202Y464883D02*
X955905Y463148D01*
G01X1008828Y530495D02*
X959938Y464027D01*
G01X1007798Y530952D02*
X959202Y464883D01*
G01X951251Y504633D02*
X951253Y504629D01*
G01X949466Y505729D02*
X950267Y504140D01*
G01X950449Y506225D02*
X951251Y504634D01*
G01X949466Y505729D02*
X950267Y504140D01*
G01X950542Y506804D02*
G03X950449Y506225I354J-354D01*
G01X949764Y507582D02*
G03X949466Y505729I1131J-1132D01*
G01X953030Y509292D02*
X950542Y506804D01*
G01X952574Y510392D02*
X949764Y507582D01*
G01X956390Y509292D02*
X953030D01*
G01X956059Y510392D02*
X952574D01*
G01X961284Y512528D02*
X956390Y509292D01*
G01X960513Y513338D02*
X956059Y510392D01*
G01X994073Y557106D02*
X961284Y512528D01*
G01X993043Y557563D02*
X960513Y513338D01*
G01X949466Y505729D02*
X950267Y504140D01*
G01X951251Y504633D02*
X951253Y504629D01*
G01X950449Y506225D02*
X951251Y504634D01*
G01X949764Y507582D02*
G03X949466Y505729I1131J-1132D01*
G01X950542Y506804D02*
G03X950449Y506225I354J-354D01*
G01X952574Y510392D02*
X949764Y507582D01*
G01X953030Y509292D02*
X950542Y506804D01*
G01X956059Y510392D02*
X952574D01*
G01X956390Y509292D02*
X953030D01*
G01X960513Y513338D02*
X956059Y510392D01*
G01X961284Y512528D02*
X956390Y509292D01*
G01X993043Y557563D02*
X960513Y513338D01*
G01X994073Y557106D02*
X961284Y512528D01*
G01X951138Y599345D02*
X951230Y599164D01*
G01X950103Y598955D02*
X950267Y598628D01*
G01X951087Y599448D02*
X951138Y599345D01*
G01X950103Y598955D02*
X950267Y598628D01*
G01X949586Y599982D02*
X950102Y598956D01*
G01X950103Y598955D02*
X950267Y598628D01*
G01X949586Y599982D02*
X950102Y598956D01*
G01X950103Y598955D02*
X950267Y598628D01*
G01X951138Y599345D02*
X951230Y599164D01*
G01X951087Y599448D02*
X951138Y599345D01*
G01X949586Y599982D02*
X950102Y598956D01*
G01X951087Y599448D02*
X951138Y599345D01*
G01X950103Y646199D02*
X950267Y645872D01*
G01X951138Y646589D02*
X951230Y646408D01*
G01X951087Y646692D02*
X951138Y646589D01*
G01X950513Y647834D02*
X951087Y646692D01*
G01X949586Y647227D02*
X950102Y646200D01*
G01X951087Y646692D02*
X951138Y646589D01*
G01X950513Y647834D02*
X951087Y646692D01*
G01X949735Y649302D02*
G03X949586Y647227I1123J-1123D01*
G01X951138Y646589D02*
X951230Y646408D01*
G01X950103Y646199D02*
X950267Y645872D01*
G01X951087Y646692D02*
X951138Y646589D01*
G01X950103Y646199D02*
X950267Y645872D01*
G01X949586Y647227D02*
X950102Y646200D01*
G01X950513Y647834D02*
X951087Y646692D01*
G01X950103Y646199D02*
X950267Y645872D01*
G01X949586Y647227D02*
X950102Y646200D01*
G01X949735Y649302D02*
G03X949586Y647227I1123J-1123D01*
G01X950103Y630451D02*
X950267Y630124D01*
G01X951138Y630841D02*
X951230Y630660D01*
G01X951087Y630944D02*
X951138Y630841D01*
G01X950513Y632086D02*
X951087Y630944D01*
G01X949586Y631478D02*
X950102Y630452D01*
G01X951087Y630944D02*
X951138Y630841D01*
G01X950513Y632086D02*
X951087Y630944D01*
G01X949735Y633586D02*
G03X949586Y631478I1139J-1140D01*
G01X950513Y632808D02*
G03Y632086I361J-361D01*
G01X952525Y636376D02*
X949735Y633586D01*
G01X952981Y635276D02*
X950513Y632808D01*
G01X956642Y636376D02*
X952525D01*
G01X956963Y635276D02*
X952981D01*
G01X1016625Y674591D02*
X956642Y636376D01*
G01X1017422Y673794D02*
X956963Y635276D01*
G01X951138Y630841D02*
X951230Y630660D01*
G01X950103Y630451D02*
X950267Y630124D01*
G01X951087Y630944D02*
X951138Y630841D01*
G01X950103Y630451D02*
X950267Y630124D01*
G01X949586Y631478D02*
X950102Y630452D01*
G01X950513Y632086D02*
X951087Y630944D01*
G01X950103Y630451D02*
X950267Y630124D01*
G01X949586Y631478D02*
X950102Y630452D01*
G01X950513Y632808D02*
G03Y632086I361J-361D01*
G01X949735Y633586D02*
G03X949586Y631478I1139J-1140D01*
G01X952981Y635276D02*
X950513Y632808D01*
G01X952525Y636376D02*
X949735Y633586D01*
G01X956963Y635276D02*
X952981D01*
G01X956642Y636376D02*
X952525D01*
G01X1017422Y673794D02*
X956963Y635276D01*
G01X1016625Y674591D02*
X956642Y636376D01*
G01X950103Y614703D02*
X950267Y614376D01*
G01X951138Y615093D02*
X951230Y614912D01*
G01X951087Y615196D02*
X951138Y615093D01*
G01X950513Y616338D02*
X951087Y615196D01*
G01X949586Y615730D02*
X950102Y614704D01*
G01X951087Y615196D02*
X951138Y615093D01*
G01X950513Y616338D02*
X951087Y615196D01*
G01X949735Y617838D02*
G03X949586Y615730I1139J-1140D01*
G01X950513Y617060D02*
G03Y616338I361J-361D01*
G01X952525Y620628D02*
X949735Y617838D01*
G01X952981Y619528D02*
X950513Y617060D01*
G01X957199Y620628D02*
X952525D01*
G01X957521Y619528D02*
X952981D01*
G01X984945Y638304D02*
X957199Y620628D01*
G01X1013485Y655181D02*
X957521Y619528D01*
G01X1012688Y655978D02*
X984945Y638304D01*
G01X1013485Y655181D02*
X957521Y619528D01*
G01X951138Y615093D02*
X951230Y614912D01*
G01X950103Y614703D02*
X950267Y614376D01*
G01X951087Y615196D02*
X951138Y615093D01*
G01X950103Y614703D02*
X950267Y614376D01*
G01X949586Y615730D02*
X950102Y614704D01*
G01X950513Y616338D02*
X951087Y615196D01*
G01X950103Y614703D02*
X950267Y614376D01*
G01X949586Y615730D02*
X950102Y614704D01*
G01X950513Y617060D02*
G03Y616338I361J-361D01*
G01X949735Y617838D02*
G03X949586Y615730I1139J-1140D01*
G01X952981Y619528D02*
X950513Y617060D01*
G01X952525Y620628D02*
X949735Y617838D01*
G01X957521Y619528D02*
X952981D01*
G01X957199Y620628D02*
X952525D01*
G01X1013485Y655181D02*
X957521Y619528D01*
G01X984945Y638304D02*
X957199Y620628D01*
G01X1012688Y655978D02*
X984945Y638304D01*
G01X950513Y600590D02*
X951087Y599448D01*
G01X950513Y601312D02*
G03Y600590I361J-361D01*
G01X949735Y602090D02*
G03X949586Y599982I1139J-1140D01*
G01X952981Y603780D02*
X950513Y601312D01*
G01X952525Y604880D02*
X949735Y602090D01*
G01X957415Y603780D02*
X952981D01*
G01X957094Y604880D02*
X952525D01*
G01X1008181Y636121D02*
X957415Y603780D01*
G01X1007384Y636918D02*
X957094Y604880D01*
G01X950513Y600590D02*
X951087Y599448D01*
G01X950513Y600590D02*
X951087Y599448D01*
G01X949735Y602090D02*
G03X949586Y599982I1139J-1140D01*
G01X950513Y601312D02*
G03Y600590I361J-361D01*
G01X952525Y604880D02*
X949735Y602090D01*
G01X952981Y603780D02*
X950513Y601312D01*
G01X957094Y604880D02*
X952525D01*
G01X957415Y603780D02*
X952981D01*
G01X1007384Y636918D02*
X957094Y604880D01*
G01X1008181Y636121D02*
X957415Y603780D01*
G01X950513Y648524D02*
G03Y647834I345J-345D01*
G01X952557Y652124D02*
X949735Y649302D01*
G01X952198Y650209D02*
X950513Y648524D01*
G01X953013Y651024D02*
X952199Y650209D01*
G01X957431Y652124D02*
X952557D01*
G01X957752Y651024D02*
X953013D01*
G01X1019384Y691592D02*
X957431Y652124D01*
G01X988999Y670930D02*
X957752Y651024D01*
G01X1020181Y690795D02*
X988999Y670930D01*
G01X950513Y648524D02*
G03Y647834I345J-345D01*
G01X952198Y650209D02*
X950513Y648524D01*
G01X952557Y652124D02*
X949735Y649302D01*
G01X953013Y651024D02*
X952199Y650209D01*
G01X952557Y652124D02*
X949735Y649302D01*
G01X957752Y651024D02*
X953013D01*
G01X957431Y652124D02*
X952557D01*
G01X988999Y670930D02*
X957752Y651024D01*
G01X1019384Y691592D02*
X957431Y652124D01*
G01X1020181Y690795D02*
X988999Y670930D01*
G01X1019384Y691592D02*
X957431Y652124D01*
G01X974249Y902443D02*
X973470Y901162D01*
G01X976380Y905946D02*
X975601Y904665D01*
G01X978511Y909449D02*
X977731Y908167D01*
G01X1000051Y944861D02*
X979862Y911670D01*
G01X974249Y902443D02*
X973470Y901162D01*
G01X976380Y905946D02*
X975601Y904665D01*
G01X978511Y909449D02*
X977731Y908167D01*
G01X1000051Y944861D02*
X979862Y911670D01*
G01X1012833Y623791D02*
X997357Y548252D01*
G01X1013869Y623366D02*
X998387Y547794D01*
G01X1013869Y623366D02*
X998387Y547794D01*
G01X1012833Y623791D02*
X997357Y548252D01*
G01X1020058Y625420D02*
X1002590Y539619D01*
G01X1021095Y624996D02*
X1003620Y539162D01*
G01X1021095Y624996D02*
X1003620Y539162D01*
G01X1020058Y625420D02*
X1002590Y539619D01*
G01X1026634Y623430D02*
X1007798Y530952D01*
G01X1022983Y599990D02*
X1008828Y530495D01*
G01X1022983Y599990D02*
X1008828Y530495D01*
G01X1026634Y623430D02*
X1007798Y530952D01*
G01X1026634Y623430D02*
X1007798Y530952D01*
G01X999292Y582727D02*
X994073Y557106D01*
G01X1006830Y625246D02*
X993043Y557563D01*
G01X1001015Y591186D02*
X999292Y582727D01*
G01X1006830Y625246D02*
X993043Y557563D01*
G01X1007867Y624822D02*
X1001015Y591186D01*
G01X1006830Y625246D02*
X993043Y557563D01*
G01X1006830Y625246D02*
X993043Y557563D01*
G01X999292Y582727D02*
X994073Y557106D01*
G01X1001015Y591186D02*
X999292Y582727D01*
G01X1007867Y624822D02*
X1001015Y591186D01*
G01X1152371Y862441D02*
X1008181Y636121D01*
G01X1151338Y862869D02*
X1007384Y636918D01*
G01X1151338Y862869D02*
X1007384Y636918D01*
G01X1152371Y862441D02*
X1008181Y636121D01*
G01X1211483Y938364D02*
X1007867Y624822D01*
G01X1151188Y847540D02*
X1006830Y625246D01*
G01X1151188Y847540D02*
X1006830Y625246D01*
G01X1211483Y938364D02*
X1007867Y624822D01*
G01X1211483Y938364D02*
X1007867Y624822D01*
G01X1211483Y938364D02*
X1007867Y624822D01*
G01X1211483Y938364D02*
X1007867Y624822D01*
G01X1211483Y938364D02*
X1007867Y624822D01*
G01X1211483Y938364D02*
X1007867Y624822D01*
G01X1211483Y938364D02*
X1007867Y624822D01*
G01X1214801Y934837D02*
X1012833Y623791D01*
G01X1114850Y778885D02*
X1013869Y623366D01*
G01X1114850Y778885D02*
X1013869Y623366D01*
G01X1214801Y934837D02*
X1012833Y623791D01*
G01X1214801Y934837D02*
X1012833Y623791D01*
G01X1208753Y915952D02*
X1020058Y625420D01*
G01X1219932Y931143D02*
X1021095Y624996D01*
G01X1219932Y931143D02*
X1021095Y624996D01*
G01X1219932Y931143D02*
X1021095Y624996D01*
G01X1219932Y931143D02*
X1021095Y624996D01*
G01X1219932Y931143D02*
X1021095Y624996D01*
G01X1208753Y915952D02*
X1020058Y625420D01*
G01X1027671Y623006D02*
X1022983Y599990D01*
G01X1176976Y854937D02*
X1026634Y623430D01*
G01X1221647Y921703D02*
X1027671Y623006D01*
G01X1221647Y921703D02*
X1027671Y623006D01*
G01X1221647Y921703D02*
X1027671Y623006D01*
G01X1221647Y921703D02*
X1027671Y623006D01*
G01X1221647Y921703D02*
X1027671Y623006D01*
G01X1221647Y921703D02*
X1027671Y623006D01*
G01X1221647Y921703D02*
X1027671Y623006D01*
G01D02*
X1022983Y599990D01*
G01X1221647Y921703D02*
X1027671Y623006D01*
G01X1176976Y854937D02*
X1026634Y623430D01*
G01X1136995Y876211D02*
X1019384Y691592D01*
G01X1079118Y783311D02*
X1020181Y690795D01*
G01X1079118Y783311D02*
X1020181Y690795D01*
G01X1136995Y876211D02*
X1019384Y691592D01*
G01X1136995Y876211D02*
X1019384Y691592D01*
G01X1141493Y870603D02*
X1016625Y674591D01*
G01X1142526Y870176D02*
X1017422Y673794D01*
G01X1142526Y870176D02*
X1017422Y673794D01*
G01X1141493Y870603D02*
X1016625Y674591D01*
G01X1146325Y865757D02*
X1012688Y655978D01*
G01X1147358Y865329D02*
X1013485Y655181D01*
G01X1147358Y865329D02*
X1013485Y655181D01*
G01X1146325Y865757D02*
X1012688Y655978D01*
G01X1025010Y903718D02*
X1024231Y902437D01*
G01X1027141Y907221D02*
X1026361Y905939D01*
G01X1043190Y933609D02*
X1028492Y909442D01*
G01X1025010Y903718D02*
X1024231Y902437D01*
G01X1027141Y907221D02*
X1026361Y905939D01*
G01X1043190Y933609D02*
X1028492Y909442D01*
G01X1015741Y906251D02*
X1014961Y904970D01*
G01X1017871Y909754D02*
X1017092Y908473D01*
G01X1032393Y933631D02*
X1019222Y911976D01*
G01X1034523Y937134D02*
X1033744Y935852D01*
G01X1015741Y906251D02*
X1014961Y904970D01*
G01X1017871Y909754D02*
X1017092Y908473D01*
G01X1032393Y933631D02*
X1019222Y911976D01*
G01X1034523Y937134D02*
X1033744Y935852D01*
G01X1024152Y934822D02*
X1023373Y933541D01*
G01X1026283Y938325D02*
X1025503Y937044D01*
G01X1024152Y934822D02*
X1023373Y933541D01*
G01X1026283Y938325D02*
X1025503Y937044D01*
G01X1004687Y920017D02*
X1003907Y918735D01*
G01X1006817Y923520D02*
X1006038Y922238D01*
G01X1031438Y964004D02*
X1008168Y925741D01*
G01X1004687Y920017D02*
X1003907Y918735D01*
G01X1006817Y923520D02*
X1006038Y922238D01*
G01X1031438Y964004D02*
X1008168Y925741D01*
G01X998419Y921381D02*
X997640Y920099D01*
G01X1000550Y924884D02*
X999770Y923602D01*
G01X1024830Y964807D02*
X1001901Y927105D01*
G01X998419Y921381D02*
X997640Y920099D01*
G01X1000550Y924884D02*
X999770Y923602D01*
G01X1024830Y964807D02*
X1001901Y927105D01*
G01X995007Y926566D02*
X994228Y925284D01*
G01X997138Y930069D02*
X996358Y928787D01*
G01X1008880Y949379D02*
X998489Y932291D01*
G01X995007Y926566D02*
X994228Y925284D01*
G01X997138Y930069D02*
X996358Y928787D01*
G01X1008880Y949379D02*
X998489Y932291D01*
G01X1036654Y940637D02*
X1035874Y939355D01*
G01X1038784Y944140D02*
X1038005Y942858D01*
G01X1036654Y940637D02*
X1035874Y939355D01*
G01X1038784Y944140D02*
X1038005Y942858D01*
G01X1028413Y941828D02*
X1027634Y940547D01*
G01X1040157Y961138D02*
X1029764Y944050D01*
G01X1028413Y941828D02*
X1027634Y940547D01*
G01X1040157Y961138D02*
X1029764Y944050D01*
G01X1033568Y967507D02*
X1032789Y966225D01*
G01X1035699Y971010D02*
X1034919Y969728D01*
G01X1037829Y974513D02*
X1037050Y973231D01*
G01X1040704Y979240D02*
X1039180Y976734D01*
G01X1033568Y967507D02*
X1032789Y966225D01*
G01X1035699Y971010D02*
X1034919Y969728D01*
G01X1037829Y974513D02*
X1037050Y973231D01*
G01X1040704Y979240D02*
X1039180Y976734D01*
G01X1026960Y968310D02*
X1026181Y967028D01*
G01X1029091Y971813D02*
X1028311Y970531D01*
G01X1031221Y975316D02*
X1030442Y974034D01*
G01X1035482Y982322D02*
X1032572Y977537D01*
G01X1090738Y1021031D02*
X1034667Y983099D01*
G01X1045813Y989311D02*
X1035482Y982322D01*
G01X1026960Y968310D02*
X1026181Y967028D01*
G01X1029091Y971813D02*
X1028311Y970531D01*
G01X1031221Y975316D02*
X1030442Y974034D01*
G01X1035482Y982322D02*
X1032572Y977537D01*
G01X1045813Y989311D02*
X1035482Y982322D01*
G01X1090738Y1021031D02*
X1034667Y983099D01*
G01X1090738Y1021031D02*
X1034667Y983099D01*
G01X1090738Y1021031D02*
X1034667Y983099D01*
G01X1090738Y1021031D02*
X1034667Y983099D01*
G01X1090738Y1021031D02*
X1034667Y983099D01*
G01X1090738Y1021031D02*
X1034667Y983099D01*
G01X1090738Y1021031D02*
X1034667Y983099D01*
G01X1090738Y1021031D02*
X1034667Y983099D01*
G01X1090738Y1021031D02*
X1034667Y983099D01*
G01X1090738Y1021031D02*
X1034667Y983099D01*
G01X1090738Y1021031D02*
X1034667Y983099D01*
G01X1090738Y1021031D02*
X1034667Y983099D01*
G01X1090738Y1021031D02*
X1034667Y983099D01*
G01X1090738Y1021031D02*
X1034667Y983099D01*
G01X1090738Y1021031D02*
X1034667Y983099D01*
G01X1011011Y952882D02*
X1010231Y951600D01*
G01X1013141Y956385D02*
X1012362Y955103D01*
G01X1015271Y959888D02*
X1014492Y958606D01*
G01X1031466Y986521D02*
X1016622Y962110D01*
G01X1011011Y952882D02*
X1010231Y951600D01*
G01X1013141Y956385D02*
X1012362Y955103D01*
G01X1015271Y959888D02*
X1014492Y958606D01*
G01X1031466Y986521D02*
X1016622Y962110D01*
G01X1002182Y948364D02*
X1001403Y947082D01*
G01X1004313Y951867D02*
X1003533Y950585D01*
G01X1006444Y955369D02*
X1005664Y954088D01*
G01X1020319Y978181D02*
X1007795Y957591D01*
G01X1022450Y981684D02*
X1021670Y980402D01*
G01X1024581Y985187D02*
X1023801Y983905D01*
G01X1002182Y948364D02*
X1001403Y947082D01*
G01X1004313Y951867D02*
X1003533Y950585D01*
G01X1006444Y955369D02*
X1005664Y954088D01*
G01X1020319Y978181D02*
X1007795Y957591D01*
G01X1022450Y981684D02*
X1021670Y980402D01*
G01X1024581Y985187D02*
X1023801Y983905D01*
G01X1024325Y998101D02*
X999909Y957958D01*
G01X1002744Y960499D02*
X1001965Y959217D01*
G01X1004874Y964002D02*
X1004095Y962720D01*
G01X1016618Y983311D02*
X1006225Y966223D01*
G01X1018748Y986814D02*
X1017969Y985532D01*
G01X1002744Y960499D02*
X1001965Y959217D01*
G01X1024325Y998101D02*
X999909Y957958D01*
G01X1004874Y964002D02*
X1004095Y962720D01*
G01X1024325Y998101D02*
X999909Y957958D01*
G01X1016618Y983311D02*
X1006225Y966223D01*
G01X1024325Y998101D02*
X999909Y957958D01*
G01X1018748Y986814D02*
X1017969Y985532D01*
G01X1024325Y998101D02*
X999909Y957958D01*
G01X1024325Y998101D02*
X999909Y957958D01*
G01X1024325Y998101D02*
X999909Y957958D01*
G01X1024325Y998101D02*
X999909Y957958D01*
G01X1090971Y1028118D02*
X1030651Y987298D01*
G01X1039392Y991884D02*
X1031466Y986521D01*
G01X1040211Y991726D02*
X1039392Y991884D01*
G01D02*
X1031466Y986521D01*
G01X1090971Y1028118D02*
X1030651Y987298D01*
G01X1040211Y991726D02*
X1039392Y991884D01*
G01X1090971Y1028118D02*
X1030651Y987298D01*
G01X1090971Y1028118D02*
X1030651Y987298D01*
G01X1090971Y1028118D02*
X1030651Y987298D01*
G01X1090971Y1028118D02*
X1030651Y987298D01*
G01X1090971Y1028118D02*
X1030651Y987298D01*
G01X1090971Y1028118D02*
X1030651Y987298D01*
G01X1090971Y1028118D02*
X1030651Y987298D01*
G01X1090971Y1028118D02*
X1030651Y987298D01*
G01X1090971Y1028118D02*
X1030651Y987298D01*
G01X1090971Y1028118D02*
X1030651Y987298D01*
G01X1090971Y1028118D02*
X1030651Y987298D01*
G01X1090971Y1028118D02*
X1030651Y987298D01*
G01X1090971Y1028118D02*
X1030651Y987298D01*
G01X1090971Y1028118D02*
X1030651Y987298D01*
G01X1029155Y992707D02*
X1025932Y987408D01*
G01X1090002Y1035205D02*
X1028340Y993484D01*
G01X1079558Y1026809D02*
X1029155Y992707D01*
G01D02*
X1025932Y987408D01*
G01X1079558Y1026809D02*
X1029155Y992707D01*
G01X1090002Y1035205D02*
X1028340Y993484D01*
G01X1090002Y1035205D02*
X1028340Y993484D01*
G01X1090002Y1035205D02*
X1028340Y993484D01*
G01X1090002Y1035205D02*
X1028340Y993484D01*
G01X1090002Y1035205D02*
X1028340Y993484D01*
G01X1090002Y1035205D02*
X1028340Y993484D01*
G01X1090002Y1035205D02*
X1028340Y993484D01*
G01X1020879Y990317D02*
X1020100Y989035D01*
G01X1023009Y993820D02*
X1022230Y992538D01*
G01X1025140Y997323D02*
X1024361Y996041D01*
G01X1032665Y1003746D02*
X1024325Y998101D01*
G01X1041425Y1008344D02*
X1025140Y997324D01*
G01X1036736Y1006501D02*
X1032665Y1003746D01*
G01X1041425Y1008344D02*
X1025140Y997324D01*
G01X1040808Y1009256D02*
X1036736Y1006501D01*
G01X1041425Y1008344D02*
X1025140Y997324D01*
G01X1020879Y990317D02*
X1020100Y989035D01*
G01X1023009Y993820D02*
X1022230Y992538D01*
G01X1025140Y997323D02*
X1024361Y996041D01*
G01X1041425Y1008344D02*
X1025140Y997324D01*
G01X1032665Y1003746D02*
X1024325Y998101D01*
G01X1036736Y1006501D02*
X1032665Y1003746D01*
G01X1040808Y1009256D02*
X1036736Y1006501D01*
G01X1138028Y875783D02*
X1079118Y783311D01*
G01X1138028Y875783D02*
X1079118Y783311D01*
G01X1045320Y937112D02*
X1044541Y935830D01*
G01X1045320Y937112D02*
X1044541Y935830D01*
G01X1047451Y940615D02*
X1046671Y939333D01*
G01X1049581Y944118D02*
X1048802Y942836D01*
G01X1061325Y963427D02*
X1050932Y946339D01*
G01X1063455Y966930D02*
X1062676Y965648D01*
G01X1065586Y970433D02*
X1064807Y969151D01*
G01X1067716Y973936D02*
X1066937Y972654D01*
G01X1069847Y977439D02*
X1069068Y976157D01*
G01X1090412Y992685D02*
X1069031Y978216D01*
G01X1075156Y981032D02*
X1069847Y977439D01*
G01X1075975Y980874D02*
X1075156Y981032D01*
G01X1078618Y983374D02*
X1077375Y982534D01*
G01X1079437Y983217D02*
X1078618Y983374D01*
G01X1082079Y985717D02*
X1080837Y984877D01*
G01X1082899Y985559D02*
X1082079Y985717D01*
G01X1047451Y940615D02*
X1046671Y939333D01*
G01X1049581Y944118D02*
X1048802Y942836D01*
G01X1061325Y963427D02*
X1050932Y946339D01*
G01X1063455Y966930D02*
X1062676Y965648D01*
G01X1065586Y970433D02*
X1064807Y969151D01*
G01X1067716Y973936D02*
X1066937Y972654D01*
G01X1069847Y977439D02*
X1069068Y976157D01*
G01X1075156Y981032D02*
X1069847Y977439D01*
G01X1090412Y992685D02*
X1069031Y978216D01*
G01X1075975Y980874D02*
X1075156Y981032D01*
G01X1090412Y992685D02*
X1069031Y978216D01*
G01X1078618Y983374D02*
X1077375Y982534D01*
G01X1090412Y992685D02*
X1069031Y978216D01*
G01X1079437Y983217D02*
X1078618Y983374D01*
G01X1090412Y992685D02*
X1069031Y978216D01*
G01X1082079Y985717D02*
X1080837Y984877D01*
G01X1090412Y992685D02*
X1069031Y978216D01*
G01X1082899Y985559D02*
X1082079Y985717D01*
G01X1090412Y992685D02*
X1069031Y978216D01*
G01X1090412Y992685D02*
X1069031Y978216D01*
G01X1050528Y963449D02*
X1040135Y946361D01*
G01X1052658Y966952D02*
X1051879Y965670D01*
G01X1054789Y970455D02*
X1054010Y969173D01*
G01X1056919Y973958D02*
X1056140Y972676D01*
G01X1059050Y977461D02*
X1058271Y976179D01*
G01X1090048Y999771D02*
X1058346Y978314D01*
G01X1067356Y983084D02*
X1059050Y977462D01*
G01X1068175Y982926D02*
X1067356Y983084D01*
G01X1070817Y985426D02*
X1069575Y984586D01*
G01X1071636Y985269D02*
X1070817Y985426D01*
G01X1050528Y963449D02*
X1040135Y946361D01*
G01X1052658Y966952D02*
X1051879Y965670D01*
G01X1054789Y970455D02*
X1054010Y969173D01*
G01X1056919Y973958D02*
X1056140Y972676D01*
G01X1059050Y977461D02*
X1058271Y976179D01*
G01X1067356Y983084D02*
X1059050Y977462D01*
G01X1090048Y999771D02*
X1058346Y978314D01*
G01X1068175Y982926D02*
X1067356Y983084D01*
G01X1090048Y999771D02*
X1058346Y978314D01*
G01X1070817Y985426D02*
X1069575Y984586D01*
G01X1090048Y999771D02*
X1058346Y978314D01*
G01X1071636Y985269D02*
X1070817Y985426D01*
G01X1090048Y999771D02*
X1058346Y978314D01*
G01X1090048Y999771D02*
X1058346Y978314D01*
G01X1090048Y999771D02*
X1058346Y978314D01*
G01X1090048Y999771D02*
X1058346Y978314D01*
G01X1042287Y964641D02*
X1041508Y963359D01*
G01X1044418Y968144D02*
X1043638Y966862D01*
G01X1046548Y971647D02*
X1045769Y970365D01*
G01X1051315Y979485D02*
X1047899Y973868D01*
G01X1087952Y1005609D02*
X1050500Y980262D01*
G01X1053990Y981295D02*
X1051315Y979485D01*
G01X1054809Y981138D02*
X1053990Y981295D01*
G01X1057452Y983638D02*
X1056210Y982798D01*
G01X1058271Y983480D02*
X1057452Y983638D01*
G01X1060914Y985981D02*
X1059671Y985140D01*
G01X1061733Y985823D02*
X1060914Y985981D01*
G01X1042287Y964641D02*
X1041508Y963359D01*
G01X1044418Y968144D02*
X1043638Y966862D01*
G01X1046548Y971647D02*
X1045769Y970365D01*
G01X1051315Y979485D02*
X1047899Y973868D01*
G01X1053990Y981295D02*
X1051315Y979485D01*
G01X1087952Y1005609D02*
X1050500Y980262D01*
G01X1054809Y981138D02*
X1053990Y981295D01*
G01X1087952Y1005609D02*
X1050500Y980262D01*
G01X1057452Y983638D02*
X1056210Y982798D01*
G01X1087952Y1005609D02*
X1050500Y980262D01*
G01X1058271Y983480D02*
X1057452Y983638D01*
G01X1087952Y1005609D02*
X1050500Y980262D01*
G01X1060914Y985981D02*
X1059671Y985140D01*
G01X1087952Y1005609D02*
X1050500Y980262D01*
G01X1061733Y985823D02*
X1060914Y985981D01*
G01X1087952Y1005609D02*
X1050500Y980262D01*
G01X1087952Y1005609D02*
X1050500Y980262D01*
G01X1087952Y1005609D02*
X1050500Y980262D01*
G01X1087952Y1005609D02*
X1050500Y980262D01*
G01X1087952Y1005609D02*
X1050500Y980262D01*
G01X1087952Y1005609D02*
X1050500Y980262D01*
G01X1087952Y1005609D02*
X1050500Y980262D01*
G01X1087952Y1005609D02*
X1050500Y980262D01*
G01X1090025Y1013945D02*
X1039889Y980017D01*
G01X1044763Y981987D02*
X1040704Y979240D01*
G01X1045527Y981839D02*
X1044763Y981987D01*
G01X1048159Y984285D02*
X1046917Y983444D01*
G01X1048923Y984137D02*
X1048159Y984285D01*
G01X1051554Y986582D02*
X1050312Y985742D01*
G01X1044763Y981987D02*
X1040704Y979240D01*
G01X1090025Y1013945D02*
X1039889Y980017D01*
G01X1045527Y981839D02*
X1044763Y981987D01*
G01X1090025Y1013945D02*
X1039889Y980017D01*
G01X1048159Y984285D02*
X1046917Y983444D01*
G01X1090025Y1013945D02*
X1039889Y980017D01*
G01X1048923Y984137D02*
X1048159Y984285D01*
G01X1090025Y1013945D02*
X1039889Y980017D01*
G01X1051554Y986582D02*
X1050312Y985742D01*
G01X1090025Y1013945D02*
X1039889Y980017D01*
G01X1090025Y1013945D02*
X1039889Y980017D01*
G01X1090025Y1013945D02*
X1039889Y980017D01*
G01X1090025Y1013945D02*
X1039889Y980017D01*
G01X1090025Y1013945D02*
X1039889Y980017D01*
G01X1090025Y1013945D02*
X1039889Y980017D01*
G01X1090025Y1013945D02*
X1039889Y980017D01*
G01X1090025Y1013945D02*
X1039889Y980017D01*
G01X1090025Y1013945D02*
X1039889Y980017D01*
G01X1090025Y1013945D02*
X1039889Y980017D01*
G01X1090025Y1013945D02*
X1039889Y980017D01*
G01X1090750Y991585D02*
X1084299Y987219D01*
G01X1090750Y991585D02*
X1084299Y987219D01*
G01X1074279Y987769D02*
X1073037Y986929D01*
G01X1075098Y987611D02*
X1074279Y987769D01*
G01X1090386Y998671D02*
X1076498Y989272D01*
G01X1074279Y987769D02*
X1073037Y986929D01*
G01X1075098Y987611D02*
X1074279Y987769D01*
G01X1090386Y998671D02*
X1076498Y989272D01*
G01X1078064Y997588D02*
X1063133Y987483D01*
G01X1078828Y997441D02*
X1078064Y997588D01*
G01X1081460Y999886D02*
X1080218Y999045D01*
G01X1082224Y999739D02*
X1081460Y999886D01*
G01X1084856Y1002184D02*
X1083614Y1001344D01*
G01X1085620Y1002037D02*
X1084856Y1002184D01*
G01X1088045Y1004343D02*
X1087009Y1003642D01*
G01X1089198Y1006453D02*
X1087951Y1005609D01*
G01X1078064Y997588D02*
X1063133Y987483D01*
G01X1078828Y997441D02*
X1078064Y997588D01*
G01X1081460Y999886D02*
X1080218Y999045D01*
G01X1082224Y999739D02*
X1081460Y999886D01*
G01X1084856Y1002184D02*
X1083614Y1001344D01*
G01X1085620Y1002037D02*
X1084856Y1002184D01*
G01X1088045Y1004343D02*
X1087009Y1003642D01*
G01X1089198Y1006453D02*
X1087951Y1005609D01*
G01X1052318Y986435D02*
X1051554Y986582D01*
G01X1054950Y988880D02*
X1053708Y988040D01*
G01X1055714Y988733D02*
X1054950Y988880D01*
G01X1076973Y1003784D02*
X1057103Y990337D01*
G01X1077792Y1003626D02*
X1076973Y1003784D01*
G01X1080435Y1006126D02*
X1079192Y1005286D01*
G01X1081254Y1005968D02*
X1080435Y1006126D01*
G01X1083896Y1008469D02*
X1082654Y1007628D01*
G01X1084716Y1008311D02*
X1083896Y1008469D01*
G01X1090363Y1012845D02*
X1086116Y1009971D01*
G01X1052318Y986435D02*
X1051554Y986582D01*
G01X1054950Y988880D02*
X1053708Y988040D01*
G01X1055714Y988733D02*
X1054950Y988880D01*
G01X1076973Y1003784D02*
X1057103Y990337D01*
G01X1077792Y1003626D02*
X1076973Y1003784D01*
G01X1080435Y1006126D02*
X1079192Y1005286D01*
G01X1081254Y1005968D02*
X1080435Y1006126D01*
G01X1083896Y1008469D02*
X1082654Y1007628D01*
G01X1084716Y1008311D02*
X1083896Y1008469D01*
G01X1090363Y1012845D02*
X1086116Y1009971D01*
G01X1046576Y989163D02*
X1045813Y989311D01*
G01X1049208Y991608D02*
X1047966Y990768D01*
G01X1049972Y991461D02*
X1049208Y991608D01*
G01X1052604Y993905D02*
X1051362Y993065D01*
G01X1053368Y993758D02*
X1052604Y993905D01*
G01X1056000Y996203D02*
X1054758Y995362D01*
G01X1056764Y996055D02*
X1056000Y996203D01*
G01X1076962Y1010383D02*
X1058154Y997659D01*
G01X1077781Y1010225D02*
X1076962Y1010383D01*
G01X1080424Y1012725D02*
X1079182Y1011884D01*
G01X1081244Y1012567D02*
X1080424Y1012725D01*
G01X1083886Y1015067D02*
X1082644Y1014227D01*
G01X1084706Y1014909D02*
X1083886Y1015067D01*
G01X1091076Y1019931D02*
X1086106Y1016569D01*
G01X1046576Y989163D02*
X1045813Y989311D01*
G01X1049208Y991608D02*
X1047966Y990768D01*
G01X1049972Y991461D02*
X1049208Y991608D01*
G01X1052604Y993905D02*
X1051362Y993065D01*
G01X1053368Y993758D02*
X1052604Y993905D01*
G01X1056000Y996203D02*
X1054758Y995362D01*
G01X1056764Y996055D02*
X1056000Y996203D01*
G01X1076962Y1010383D02*
X1058154Y997659D01*
G01X1077781Y1010225D02*
X1076962Y1010383D01*
G01X1080424Y1012725D02*
X1079182Y1011884D01*
G01X1081244Y1012567D02*
X1080424Y1012725D01*
G01X1083886Y1015067D02*
X1082644Y1014227D01*
G01X1084706Y1014909D02*
X1083886Y1015067D01*
G01X1091076Y1019931D02*
X1086106Y1016569D01*
G01X1042853Y994227D02*
X1041611Y993386D01*
G01X1043673Y994069D02*
X1042853Y994227D01*
G01X1046315Y996570D02*
X1045073Y995729D01*
G01X1047135Y996412D02*
X1046315Y996570D01*
G01X1075765Y1016499D02*
X1048535Y998072D01*
G01X1076528Y1016352D02*
X1075765Y1016499D01*
G01X1079160Y1018797D02*
X1077918Y1017956D01*
G01X1079924Y1018649D02*
X1079160Y1018797D01*
G01X1082556Y1021095D02*
X1081314Y1020254D01*
G01X1083320Y1020947D02*
X1082556Y1021095D01*
G01X1085951Y1023392D02*
X1084709Y1022552D01*
G01X1086715Y1023245D02*
X1085951Y1023392D01*
G01X1042853Y994227D02*
X1041611Y993386D01*
G01X1043673Y994069D02*
X1042853Y994227D01*
G01X1046315Y996570D02*
X1045073Y995729D01*
G01X1047135Y996412D02*
X1046315Y996570D01*
G01X1075765Y1016499D02*
X1048535Y998072D01*
G01X1076528Y1016352D02*
X1075765Y1016499D01*
G01X1079160Y1018797D02*
X1077918Y1017956D01*
G01X1079924Y1018649D02*
X1079160Y1018797D01*
G01X1082556Y1021095D02*
X1081314Y1020254D01*
G01X1083320Y1020947D02*
X1082556Y1021095D01*
G01X1085951Y1023392D02*
X1084709Y1022552D01*
G01X1086715Y1023245D02*
X1085951Y1023392D01*
G01X1080377Y1026651D02*
X1079558Y1026809D01*
G01X1083020Y1029152D02*
X1081777Y1028311D01*
G01X1083839Y1028994D02*
X1083020Y1029152D01*
G01X1086482Y1031494D02*
X1085239Y1030654D01*
G01X1087301Y1031336D02*
X1086482Y1031494D01*
G01X1080377Y1026651D02*
X1079558Y1026809D01*
G01X1083020Y1029152D02*
X1081777Y1028311D01*
G01X1083839Y1028994D02*
X1083020Y1029152D01*
G01X1086482Y1031494D02*
X1085239Y1030654D01*
G01X1087301Y1031336D02*
X1086482Y1031494D01*
G01X1089943Y1042504D02*
X1040808Y1009256D01*
G01X1047794Y1012654D02*
X1041425Y1008344D01*
G01X1048558Y1012506D02*
X1047794Y1012654D01*
G01X1051190Y1014951D02*
X1049948Y1014111D01*
G01X1051954Y1014804D02*
X1051190Y1014951D01*
G01X1054586Y1017249D02*
X1053343Y1016409D01*
G01X1055349Y1017102D02*
X1054586Y1017249D01*
G01X1057981Y1019547D02*
X1056739Y1018706D01*
G01X1058745Y1019400D02*
X1057981Y1019547D01*
G01X1078209Y1033235D02*
X1060135Y1021004D01*
G01X1079028Y1033077D02*
X1078209Y1033235D01*
G01X1047794Y1012654D02*
X1041425Y1008344D01*
G01X1089943Y1042504D02*
X1040808Y1009256D01*
G01X1048558Y1012506D02*
X1047794Y1012654D01*
G01X1089943Y1042504D02*
X1040808Y1009256D01*
G01X1051190Y1014951D02*
X1049948Y1014111D01*
G01X1089943Y1042504D02*
X1040808Y1009256D01*
G01X1051954Y1014804D02*
X1051190Y1014951D01*
G01X1089943Y1042504D02*
X1040808Y1009256D01*
G01X1054586Y1017249D02*
X1053343Y1016409D01*
G01X1089943Y1042504D02*
X1040808Y1009256D01*
G01X1055349Y1017102D02*
X1054586Y1017249D01*
G01X1089943Y1042504D02*
X1040808Y1009256D01*
G01X1057981Y1019547D02*
X1056739Y1018706D01*
G01X1089943Y1042504D02*
X1040808Y1009256D01*
G01X1058745Y1019400D02*
X1057981Y1019547D01*
G01X1089943Y1042504D02*
X1040808Y1009256D01*
G01X1078209Y1033235D02*
X1060135Y1021004D01*
G01X1089943Y1042504D02*
X1040808Y1009256D01*
G01X1079028Y1033077D02*
X1078209Y1033235D01*
G01X1089943Y1042504D02*
X1040808Y1009256D01*
G01X1089943Y1042504D02*
X1040808Y1009256D01*
G01X1089943Y1042504D02*
X1040808Y1009256D01*
G01X1089943Y1042504D02*
X1040808Y1009256D01*
G01X1089943Y1042504D02*
X1040808Y1009256D01*
G01X1089943Y1042504D02*
X1040808Y1009256D01*
G01X1081671Y1035577D02*
X1080428Y1034737D01*
G01X1082490Y1035419D02*
X1081671Y1035577D01*
G01X1085132Y1037920D02*
X1083890Y1037079D01*
G01X1085952Y1037762D02*
X1085132Y1037920D01*
G01X1090281Y1041404D02*
X1087352Y1039422D01*
G01X1081671Y1035577D02*
X1080428Y1034737D01*
G01X1082490Y1035419D02*
X1081671Y1035577D01*
G01X1085132Y1037920D02*
X1083890Y1037079D01*
G01X1085952Y1037762D02*
X1085132Y1037920D01*
G01X1090281Y1041404D02*
X1087352Y1039422D01*
G01X1102701Y46866D02*
X1102217Y46382D01*
G01X1101923Y47644D02*
X1100992Y46713D01*
G01X1104188Y47482D02*
G03X1102701Y46866I0J-2103D01*
G01X1104187Y48582D02*
G03X1101923Y47644I1J-3203D01*
G01X1117181Y47482D02*
X1104188D01*
G01X1116725Y48582D02*
X1104187D01*
G01X1124385Y54686D02*
X1117181Y47482D01*
G01X1123525Y55382D02*
X1116725Y48582D01*
G01X1125205Y55949D02*
X1124385Y54686D01*
G01X1148328Y93575D02*
X1123525Y55382D01*
G01X1127438Y59387D02*
X1126621Y58129D01*
G01X1148328Y93575D02*
X1123525Y55382D01*
G01X1129671Y62826D02*
X1128854Y61568D01*
G01X1148328Y93575D02*
X1123525Y55382D01*
G01X1149124Y92779D02*
X1131087Y65006D01*
G01X1148328Y93575D02*
X1123525Y55382D01*
G01X1101923Y47644D02*
X1100992Y46713D01*
G01X1102701Y46866D02*
X1102217Y46382D01*
G01X1104187Y48582D02*
G03X1101923Y47644I1J-3203D01*
G01X1104188Y47482D02*
G03X1102701Y46866I0J-2103D01*
G01X1116725Y48582D02*
X1104187D01*
G01X1117181Y47482D02*
X1104188D01*
G01X1123525Y55382D02*
X1116725Y48582D01*
G01X1124385Y54686D02*
X1117181Y47482D01*
G01X1148328Y93575D02*
X1123525Y55382D01*
G01X1125205Y55949D02*
X1124385Y54686D01*
G01X1127438Y59387D02*
X1126621Y58129D01*
G01X1129671Y62826D02*
X1128854Y61568D01*
G01X1149124Y92779D02*
X1131087Y65006D01*
G01X1119151Y139209D02*
X1118848Y139812D01*
G01X1119975Y140021D02*
X1119811Y140348D01*
G01X1120110Y139754D02*
X1119976Y140020D01*
G01X1120950Y138100D02*
G02X1119151Y139209I0J2013D01*
G01X1121009Y139200D02*
G02X1120110Y139754I0J1007D01*
G01X1125405Y138100D02*
X1120950D01*
G01X1125514Y139200D02*
X1121009D01*
G01X1191379Y125016D02*
X1125405Y138100D01*
G01X1141125Y136104D02*
X1125514Y139200D01*
G01X1119975Y140021D02*
X1119811Y140348D01*
G01X1119151Y139209D02*
X1118848Y139812D01*
G01X1120110Y139754D02*
X1119976Y140020D01*
G01X1119151Y139209D02*
X1118848Y139812D01*
G01X1121009Y139200D02*
G02X1120110Y139754I0J1007D01*
G01X1120950Y138100D02*
G02X1119151Y139209I0J2013D01*
G01X1125514Y139200D02*
X1121009D01*
G01X1125405Y138100D02*
X1120950D01*
G01X1141125Y136104D02*
X1125514Y139200D01*
G01X1191379Y125016D02*
X1125405Y138100D01*
G01X1191379Y125016D02*
X1125405Y138100D01*
G01X1191379Y125016D02*
X1125405Y138100D01*
G01X1215833Y934404D02*
X1114850Y778885D01*
G01X1215833Y934404D02*
X1114850Y778885D01*
G01X1131661Y966604D02*
X1144911Y906835D01*
G01X1131661Y966604D02*
X1144911Y906835D01*
G01X1131661Y966604D02*
X1144911Y906835D01*
G01X1133245Y954375D02*
X1140796Y920311D01*
G01X1131661Y966604D02*
X1144911Y906835D01*
G01X1132340Y958456D02*
X1132665Y956992D01*
G01X1131661Y966604D02*
X1144911Y906835D01*
G01X1131436Y962537D02*
X1131760Y961073D01*
G01X1131661Y966604D02*
X1144911Y906835D01*
G01X1130531Y966618D02*
X1130856Y965154D01*
G01X1131661Y966604D02*
X1144911Y906835D01*
G01X1136010Y988740D02*
X1130531Y966618D01*
G01X1137151Y988770D02*
X1131661Y966604D01*
G01D02*
X1144911Y906835D01*
G01X1133245Y954375D02*
X1140796Y920311D01*
G01X1132340Y958456D02*
X1132665Y956992D01*
G01X1131436Y962537D02*
X1131760Y961073D01*
G01X1130531Y966618D02*
X1130856Y965154D01*
G01X1137151Y988770D02*
X1131661Y966604D01*
G01X1136010Y988740D02*
X1130531Y966618D01*
G01X1135408Y990704D02*
X1136010Y988741D01*
G01X1134133Y991585D02*
X1135408Y990704D01*
G01X1134477Y992685D02*
X1136348Y991392D01*
G01X1127699Y991585D02*
X1134133D01*
G01X1127699Y992685D02*
X1134477D01*
G01X1127072Y990958D02*
G02X1127699Y991585I627J0D01*
G01X1125972Y990958D02*
G02X1127699Y992685I1727J0D01*
G01X1127072Y989092D02*
Y990958D01*
G01X1125972Y989092D02*
Y990958D01*
G01X1135408Y990704D02*
X1136010Y988741D01*
G01X1134477Y992685D02*
X1136348Y991392D01*
G01X1134133Y991585D02*
X1135408Y990704D01*
G01X1127699Y992685D02*
X1134477D01*
G01X1127699Y991585D02*
X1134133D01*
G01X1125972Y990958D02*
G02X1127699Y992685I1727J0D01*
G01X1127072Y990958D02*
G02X1127699Y991585I627J0D01*
G01X1125972Y989092D02*
Y990958D01*
G01X1127072Y989092D02*
Y990958D01*
G01X1131636Y998671D02*
X1137945D01*
G01X1131636Y999771D02*
X1138288D01*
G01X1131009Y998044D02*
G02X1131636Y998671I627J0D01*
G01X1129909Y998044D02*
G02X1131636Y999771I1727J0D01*
G01X1131009Y996178D02*
Y998044D01*
G01X1129909Y996178D02*
Y998044D01*
G01X1131636Y999771D02*
X1138288D01*
G01X1131636Y998671D02*
X1137945D01*
G01X1129909Y998044D02*
G02X1131636Y999771I1727J0D01*
G01X1131009Y998044D02*
G02X1131636Y998671I627J0D01*
G01X1129909Y996178D02*
Y998044D01*
G01X1131009Y996178D02*
Y998044D01*
G01X1135698Y1005758D02*
X1144405Y999742D01*
G01X1136042Y1006858D02*
X1145345Y1000431D01*
G01X1127699Y1005758D02*
X1135698D01*
G01X1127699Y1006858D02*
X1136042D01*
G01X1127072Y1005131D02*
G02X1127699Y1005758I627J0D01*
G01X1125972Y1005131D02*
G02X1127699Y1006858I1727J0D01*
G01X1127072Y1003265D02*
Y1005131D01*
G01X1125972Y1003265D02*
Y1005131D01*
G01X1136042Y1006858D02*
X1145345Y1000431D01*
G01X1135698Y1005758D02*
X1144405Y999742D01*
G01X1127699Y1006858D02*
X1136042D01*
G01X1127699Y1005758D02*
X1135698D01*
G01X1125972Y1005131D02*
G02X1127699Y1006858I1727J0D01*
G01X1127072Y1005131D02*
G02X1127699Y1005758I627J0D01*
G01X1125972Y1003265D02*
Y1005131D01*
G01X1127072Y1003265D02*
Y1005131D01*
G01X1131636Y1013945D02*
X1138087D01*
G01X1131636Y1012845D02*
X1137743D01*
G01X1129909Y1012218D02*
G02X1131636Y1013945I1727J0D01*
G01X1131009Y1012218D02*
G02X1131636Y1012845I627J0D01*
G01X1129909Y1010352D02*
Y1012218D01*
G01X1131009Y1010352D02*
Y1012218D01*
G01X1131636Y1012845D02*
X1137743D01*
G01X1131636Y1013945D02*
X1138087D01*
G01X1131009Y1012218D02*
G02X1131636Y1012845I627J0D01*
G01X1129909Y1012218D02*
G02X1131636Y1013945I1727J0D01*
G01X1131009Y1010352D02*
Y1012218D01*
G01X1129909Y1010352D02*
Y1012218D01*
G01X1127699Y1021031D02*
X1142858D01*
G01X1127699Y1019931D02*
X1142747D01*
G01X1125972Y1019304D02*
G02X1127699Y1021031I1727J0D01*
G01X1127072Y1019304D02*
G02X1127699Y1019931I627J0D01*
G01X1125972Y1017438D02*
Y1019304D01*
G01X1127072Y1017438D02*
Y1019304D01*
G01X1127699Y1019931D02*
X1142747D01*
G01X1127699Y1021031D02*
X1142858D01*
G01X1127072Y1019304D02*
G02X1127699Y1019931I627J0D01*
G01X1125972Y1019304D02*
G02X1127699Y1021031I1727J0D01*
G01X1127072Y1017438D02*
Y1019304D01*
G01X1125972Y1017438D02*
Y1019304D01*
G01X1131636Y1027018D02*
X1141832D01*
G01X1131636Y1028118D02*
X1141943D01*
G01X1131009Y1026391D02*
G02X1131636Y1027018I627J0D01*
G01X1129909Y1026391D02*
G02X1131636Y1028118I1727J0D01*
G01X1131009Y1024525D02*
Y1026391D01*
G01X1129909Y1024525D02*
Y1026391D01*
G01X1131636Y1028118D02*
X1141943D01*
G01X1131636Y1027018D02*
X1141832D01*
G01X1129909Y1026391D02*
G02X1131636Y1028118I1727J0D01*
G01X1131009Y1026391D02*
G02X1131636Y1027018I627J0D01*
G01X1129909Y1024525D02*
Y1026391D01*
G01X1131009Y1024525D02*
Y1026391D01*
G01X1127699Y1034104D02*
X1138532D01*
G01X1127072Y1033477D02*
G02X1127699Y1034104I627J0D01*
G01X1125972Y1033477D02*
G02X1127699Y1035204I1727J0D01*
G01X1127072Y1031611D02*
Y1033477D01*
G01X1125972Y1031611D02*
Y1033477D01*
G01X1127699Y1034104D02*
X1138532D01*
G01X1125972Y1033477D02*
G02X1127699Y1035204I1727J0D01*
G01X1127072Y1033477D02*
G02X1127699Y1034104I627J0D01*
G01X1125972Y1031611D02*
Y1033477D01*
G01X1127072Y1031611D02*
Y1033477D01*
G01X1096999Y992685D02*
X1090412D01*
G01X1096999Y991585D02*
X1090750D01*
G01X1098726Y990958D02*
G03X1096999Y992685I-1727J0D01*
G01X1097626Y990958D02*
G03X1096999Y991585I-627J0D01*
G01X1098726Y989092D02*
Y990958D01*
G01X1097626Y989092D02*
Y990958D01*
G01X1096999Y991585D02*
X1090750D01*
G01X1096999Y992685D02*
X1090412D01*
G01X1097626Y990958D02*
G03X1096999Y991585I-627J0D01*
G01X1098726Y990958D02*
G03X1096999Y992685I-1727J0D01*
G01X1097626Y989092D02*
Y990958D01*
G01X1098726Y989092D02*
Y990958D01*
G01X1100936Y999771D02*
X1090048D01*
G01X1100936Y998671D02*
X1090386D01*
G01X1102663Y998044D02*
G03X1100936Y999771I-1727J0D01*
G01X1101563Y998044D02*
G03X1100936Y998671I-627J0D01*
G01X1102663Y996178D02*
Y998044D01*
G01X1101563Y996178D02*
Y998044D01*
G01X1100936Y998671D02*
X1090386D01*
G01X1100936Y999771D02*
X1090048D01*
G01X1101563Y998044D02*
G03X1100936Y998671I-627J0D01*
G01X1102663Y998044D02*
G03X1100936Y999771I-1727J0D01*
G01X1101563Y996178D02*
Y998044D01*
G01X1102663Y996178D02*
Y998044D01*
G01X1087951Y1005609D02*
X1087952D01*
G01X1090136Y1005758D02*
X1088045Y1004343D01*
G01X1090136Y1005758D02*
X1088045Y1004343D01*
G01X1089799Y1006858D02*
X1089198Y1006453D01*
G01X1090136Y1005758D02*
X1088045Y1004343D01*
G01X1096999Y1005758D02*
X1090136D01*
G01X1096999Y1006858D02*
X1089799D01*
G01X1096999Y1005758D02*
X1090136D01*
G01X1098726Y1005131D02*
G03X1096999Y1006858I-1727J0D01*
G01X1097626Y1005131D02*
G03X1096999Y1005758I-627J0D01*
G01X1098726Y1003265D02*
Y1005131D01*
G01X1097626Y1003265D02*
Y1005131D01*
G01X1090136Y1005758D02*
X1088045Y1004343D01*
G01X1087951Y1005609D02*
X1087952D01*
G01X1089799Y1006858D02*
X1089198Y1006453D01*
G01X1096999Y1005758D02*
X1090136D01*
G01X1089799Y1006858D02*
X1089198Y1006453D01*
G01X1096999Y1006858D02*
X1089799D01*
G01X1097626Y1005131D02*
G03X1096999Y1005758I-627J0D01*
G01X1098726Y1005131D02*
G03X1096999Y1006858I-1727J0D01*
G01X1097626Y1003265D02*
Y1005131D01*
G01X1098726Y1003265D02*
Y1005131D01*
G01X1100936Y1013945D02*
X1090025D01*
G01X1100936Y1012845D02*
X1090363D01*
G01X1102663Y1012218D02*
G03X1100936Y1013945I-1727J0D01*
G01X1101563Y1012218D02*
G03X1100936Y1012845I-627J0D01*
G01X1102663Y1010352D02*
Y1012218D01*
G01X1101563Y1010352D02*
Y1012218D01*
G01X1100936Y1012845D02*
X1090363D01*
G01X1100936Y1013945D02*
X1090025D01*
G01X1101563Y1012218D02*
G03X1100936Y1012845I-627J0D01*
G01X1102663Y1012218D02*
G03X1100936Y1013945I-1727J0D01*
G01X1101563Y1010352D02*
Y1012218D01*
G01X1102663Y1010352D02*
Y1012218D01*
G01X1096999Y1021031D02*
X1090738D01*
G01X1096999Y1019931D02*
X1091076D01*
G01X1098726Y1019304D02*
G03X1096999Y1021031I-1727J0D01*
G01X1097626Y1019304D02*
G03X1096999Y1019931I-627J0D01*
G01X1098726Y1017438D02*
Y1019304D01*
G01X1097626Y1017438D02*
Y1019304D01*
G01X1096999Y1019931D02*
X1091076D01*
G01X1096999Y1021031D02*
X1090738D01*
G01X1097626Y1019304D02*
G03X1096999Y1019931I-627J0D01*
G01X1098726Y1019304D02*
G03X1096999Y1021031I-1727J0D01*
G01X1097626Y1017438D02*
Y1019304D01*
G01X1098726Y1017438D02*
Y1019304D01*
G01X1091309Y1027018D02*
X1088105Y1024850D01*
G01X1100936Y1028118D02*
X1090971D01*
G01X1100936Y1027018D02*
X1091309D01*
G01X1102663Y1026391D02*
G03X1100936Y1028118I-1727J0D01*
G01X1101563Y1026391D02*
G03X1100936Y1027018I-627J0D01*
G01X1102663Y1024525D02*
Y1026391D01*
G01X1101563Y1024525D02*
Y1026391D01*
G01X1091309Y1027018D02*
X1088105Y1024850D01*
G01X1100936Y1027018D02*
X1091309D01*
G01X1100936Y1028118D02*
X1090971D01*
G01X1101563Y1026391D02*
G03X1100936Y1027018I-627J0D01*
G01X1102663Y1026391D02*
G03X1100936Y1028118I-1727J0D01*
G01X1101563Y1024525D02*
Y1026391D01*
G01X1102663Y1024525D02*
Y1026391D01*
G01X1090339Y1034104D02*
X1088701Y1032996D01*
G01X1096998Y1034105D02*
X1090340D01*
G01X1098726Y1033477D02*
G03X1096998Y1035205I-1728J0D01*
G01X1097626Y1033477D02*
G03X1096998Y1034105I-628J0D01*
G01X1098726Y1031611D02*
Y1033477D01*
G01X1097626Y1031611D02*
Y1033477D01*
G01X1090339Y1034104D02*
X1088701Y1032996D01*
G01X1096998Y1034105D02*
X1090340D01*
G01X1097626Y1033477D02*
G03X1096998Y1034105I-628J0D01*
G01X1098726Y1033477D02*
G03X1096998Y1035205I-1728J0D01*
G01X1097626Y1031611D02*
Y1033477D01*
G01X1098726Y1031611D02*
Y1033477D01*
G01X1127699Y1035204D02*
X1138643D01*
G01X1127699D02*
X1138643D01*
G01X1131636Y1041191D02*
X1143825D01*
G01X1131636Y1042291D02*
X1143936D01*
G01X1131009Y1040564D02*
G02X1131636Y1041191I627J0D01*
G01X1129909Y1040564D02*
G02X1131636Y1042291I1727J0D01*
G01X1131009Y1038698D02*
Y1040564D01*
G01X1129909Y1038698D02*
Y1040564D01*
G01X1131636Y1042291D02*
X1143936D01*
G01X1131636Y1041191D02*
X1143825D01*
G01X1129909Y1040564D02*
G02X1131636Y1042291I1727J0D01*
G01X1131009Y1040564D02*
G02X1131636Y1041191I627J0D01*
G01X1129909Y1038698D02*
Y1040564D01*
G01X1131009Y1038698D02*
Y1040564D01*
G01X1096998Y1035205D02*
X1090002D01*
G01X1096998D02*
X1090002D01*
G01X1100723Y1042504D02*
X1089943D01*
G01X1100723Y1041404D02*
X1090281D01*
G01X1102663Y1040564D02*
G03X1100723Y1042504I-1940J0D01*
G01X1101563Y1040564D02*
G03X1100723Y1041404I-840J0D01*
G01X1102663Y1038698D02*
Y1040564D01*
G01X1101563Y1038698D02*
Y1040564D01*
G01X1100723Y1041404D02*
X1090281D01*
G01X1100723Y1042504D02*
X1089943D01*
G01X1101563Y1040564D02*
G03X1100723Y1041404I-840J0D01*
G01X1102663Y1040564D02*
G03X1100723Y1042504I-1940J0D01*
G01X1101563Y1038698D02*
Y1040564D01*
G01X1102663Y1038698D02*
Y1040564D01*
G01X1167206Y104524D02*
X1149124Y92779D01*
G01X1166773Y105556D02*
X1148328Y93575D01*
G01X1204940Y112895D02*
X1167206Y104524D01*
G01X1242664Y122391D02*
X1166773Y105556D01*
G01X1242664Y122391D02*
X1166773Y105556D01*
G01X1242664Y122391D02*
X1166773Y105556D01*
G01D02*
X1148328Y93575D01*
G01X1167206Y104524D02*
X1149124Y92779D01*
G01X1242664Y122391D02*
X1166773Y105556D01*
G01X1204940Y112895D02*
X1167206Y104524D01*
G01X1145147Y135307D02*
X1143676Y135598D01*
G01X1191374Y126139D02*
X1147697Y134801D01*
G01X1145147Y135307D02*
X1143676Y135598D01*
G01X1191374Y126139D02*
X1147697Y134801D01*
G01X1143784Y906835D02*
X1136995Y876211D01*
G01X1144911Y906835D02*
X1138028Y875783D01*
G01X1144911Y906835D02*
X1138028Y875783D01*
G01X1143784Y906835D02*
X1136995Y876211D01*
G01X1149563Y907294D02*
X1141493Y870603D01*
G01X1150690Y907295D02*
X1142526Y870176D01*
G01X1150690Y907295D02*
X1142526Y870176D01*
G01X1149563Y907294D02*
X1141493Y870603D01*
G01X1155591Y907555D02*
X1146325Y865757D01*
G01X1156718Y907555D02*
X1147358Y865329D01*
G01X1156718Y907555D02*
X1147358Y865329D01*
G01X1155591Y907555D02*
X1146325Y865757D01*
G01X1161936Y905590D02*
X1152371Y862441D01*
G01X1160809Y905590D02*
X1151338Y862869D01*
G01X1160809Y905590D02*
X1151338Y862869D01*
G01X1161936Y905590D02*
X1152371Y862441D01*
G01X1153464Y851046D02*
X1152647Y849788D01*
G01X1155741Y854551D02*
X1154924Y853293D01*
G01X1201646Y925239D02*
X1157201Y856799D01*
G01X1153464Y851046D02*
X1152647Y849788D01*
G01X1155741Y854551D02*
X1154924Y853293D01*
G01X1201646Y925239D02*
X1157201Y856799D01*
G01X1179253Y858444D02*
X1178436Y857186D01*
G01X1181530Y861950D02*
X1180713Y860692D01*
G01X1213129Y910609D02*
X1182989Y864197D01*
G01X1179253Y858444D02*
X1178436Y857186D01*
G01X1181530Y861950D02*
X1180713Y860692D01*
G01X1213129Y910609D02*
X1182989Y864197D01*
G01X1143186Y909533D02*
X1143784Y906835D01*
G01X1142281Y913614D02*
X1142606Y912149D01*
G01X1141376Y917695D02*
X1141701Y916230D01*
G01X1143186Y909533D02*
X1143784Y906835D01*
G01X1142281Y913614D02*
X1142606Y912149D01*
G01X1141376Y917695D02*
X1141701Y916230D01*
G01X1148895Y910308D02*
X1149563Y907294D01*
G01X1137502Y966797D02*
X1150690Y907295D01*
G01X1147990Y914389D02*
X1148315Y912925D01*
G01X1137502Y966797D02*
X1150690Y907295D01*
G01X1147086Y918470D02*
X1147410Y917006D01*
G01X1137502Y966797D02*
X1150690Y907295D01*
G01X1139085Y954569D02*
X1146506Y921087D01*
G01X1137502Y966797D02*
X1150690Y907295D01*
G01X1137502Y966797D02*
X1150690Y907295D01*
G01X1137502Y966797D02*
X1150690Y907295D01*
G01X1137502Y966797D02*
X1150690Y907295D01*
G01X1137502Y966797D02*
X1150690Y907295D01*
G01X1148895Y910308D02*
X1149563Y907294D01*
G01X1147990Y914389D02*
X1148315Y912925D01*
G01X1147086Y918470D02*
X1147410Y917006D01*
G01X1139085Y954569D02*
X1146506Y921087D01*
G01X1152853Y919902D02*
X1155591Y907555D01*
G01X1143064Y969136D02*
X1156718Y907555D01*
G01X1151948Y923983D02*
X1152273Y922518D01*
G01X1143064Y969136D02*
X1156718Y907555D01*
G01X1151044Y928064D02*
X1151368Y926599D01*
G01X1143064Y969136D02*
X1156718Y907555D01*
G01X1144648Y956908D02*
X1150463Y930680D01*
G01X1143064Y969136D02*
X1156718Y907555D01*
G01X1143064Y969136D02*
X1156718Y907555D01*
G01X1143064Y969136D02*
X1156718Y907555D01*
G01X1143064Y969136D02*
X1156718Y907555D01*
G01X1143064Y969136D02*
X1156718Y907555D01*
G01X1152853Y919902D02*
X1155591Y907555D01*
G01X1151948Y923983D02*
X1152273Y922518D01*
G01X1151044Y928064D02*
X1151368Y926599D01*
G01X1144648Y956908D02*
X1150463Y930680D01*
G01X1147893Y968934D02*
X1161936Y905590D01*
G01X1158595Y915575D02*
X1160809Y905590D01*
G01X1157690Y919656D02*
X1158015Y918192D01*
G01X1156786Y923737D02*
X1157110Y922273D01*
G01X1149476Y956706D02*
X1156205Y926354D01*
G01X1158595Y915575D02*
X1160809Y905590D01*
G01X1147893Y968934D02*
X1161936Y905590D01*
G01X1157690Y919656D02*
X1158015Y918192D01*
G01X1147893Y968934D02*
X1161936Y905590D01*
G01X1156786Y923737D02*
X1157110Y922273D01*
G01X1147893Y968934D02*
X1161936Y905590D01*
G01X1149476Y956706D02*
X1156205Y926354D01*
G01X1147893Y968934D02*
X1161936Y905590D01*
G01X1147893Y968934D02*
X1161936Y905590D01*
G01X1147893Y968934D02*
X1161936Y905590D01*
G01X1147893Y968934D02*
X1161936Y905590D01*
G01X1138180Y958650D02*
X1138505Y957186D01*
G01X1137276Y962731D02*
X1137600Y961267D01*
G01X1136371Y966812D02*
X1136696Y965348D01*
G01X1141874Y988846D02*
X1136371Y966812D01*
G01X1143053Y989021D02*
X1137502Y966797D01*
G01X1138180Y958650D02*
X1138505Y957186D01*
G01X1137276Y962731D02*
X1137600Y961267D01*
G01X1136371Y966812D02*
X1136696Y965348D01*
G01X1143053Y989021D02*
X1137502Y966797D01*
G01X1141874Y988846D02*
X1136371Y966812D01*
G01X1143743Y960989D02*
X1144067Y959525D01*
G01X1142838Y965070D02*
X1143163Y963606D01*
G01X1141933Y969151D02*
X1142258Y967687D01*
G01X1147255Y990475D02*
X1141933Y969151D01*
G01X1148397Y990506D02*
X1143064Y969136D01*
G01X1143743Y960989D02*
X1144067Y959525D01*
G01X1142838Y965070D02*
X1143163Y963606D01*
G01X1141933Y969151D02*
X1142258Y967687D01*
G01X1148397Y990506D02*
X1143064Y969136D01*
G01X1147255Y990475D02*
X1141933Y969151D01*
G01X1148572Y960787D02*
X1148896Y959323D01*
G01X1147667Y964868D02*
X1147991Y963404D01*
G01X1146762Y968949D02*
X1147087Y967485D01*
G01X1153895Y992987D02*
X1147893Y968934D01*
G01X1152753Y992956D02*
X1146762Y968949D01*
G01X1148572Y960787D02*
X1148896Y959323D01*
G01X1147667Y964868D02*
X1147991Y963404D01*
G01X1146762Y968949D02*
X1147087Y967485D01*
G01X1152753Y992956D02*
X1146762Y968949D01*
G01X1153895Y992987D02*
X1147893Y968934D01*
G01X1136348Y991392D02*
X1137152Y988771D01*
G01X1136348Y991392D02*
X1137152Y988771D01*
G01X1139486Y997607D02*
X1141874Y988847D01*
G01X1140442Y998284D02*
X1142896Y989283D01*
G01X1137945Y998671D02*
X1139486Y997607D01*
G01X1138288Y999771D02*
X1140442Y998284D01*
G01D02*
X1142896Y989283D01*
G01X1139486Y997607D02*
X1141874Y988847D01*
G01X1138288Y999771D02*
X1140442Y998284D01*
G01X1137945Y998671D02*
X1139486Y997607D01*
G01X1145830Y995108D02*
X1147255Y990475D01*
G01X1146882Y995432D02*
X1148397Y990506D01*
G01X1145117Y997427D02*
X1145830Y995108D01*
G01X1145345Y1000431D02*
X1146882Y995432D01*
G01X1144405Y999742D02*
X1145116Y997427D01*
G01X1145345Y1000431D02*
X1146882Y995432D01*
G01D02*
X1148397Y990506D01*
G01X1145830Y995108D02*
X1147255Y990475D01*
G01X1145345Y1000431D02*
X1146882Y995432D01*
G01X1145117Y997427D02*
X1145830Y995108D01*
G01X1144405Y999742D02*
X1145116Y997427D01*
G01X1149980Y1005719D02*
X1153895Y992987D01*
G01X1149040Y1005031D02*
X1152753Y992956D01*
G01X1144017Y1009843D02*
X1149980Y1005719D01*
G01X1137743Y1012845D02*
X1149040Y1005031D01*
G01X1138087Y1013945D02*
X1144017Y1009843D01*
G01X1137743Y1012845D02*
X1149040Y1005031D01*
G01D02*
X1152753Y992956D01*
G01X1149980Y1005719D02*
X1153895Y992987D01*
G01X1137743Y1012845D02*
X1149040Y1005031D01*
G01X1144017Y1009843D02*
X1149980Y1005719D01*
G01X1138087Y1013945D02*
X1144017Y1009843D01*
G01X1142858Y1021031D02*
X1192361Y1010980D01*
G01X1142747Y1019931D02*
X1191957Y1009939D01*
G01X1142747Y1019931D02*
X1191957Y1009939D01*
G01X1142858Y1021031D02*
X1192361Y1010980D01*
G01X1172562Y1020779D02*
X1191217Y1016992D01*
G01X1141943Y1028118D02*
X1191621Y1018033D01*
G01X1168466Y1021611D02*
X1169936Y1021312D01*
G01X1141943Y1028118D02*
X1191621Y1018033D01*
G01X1164369Y1022442D02*
X1165839Y1022144D01*
G01X1141943Y1028118D02*
X1191621Y1018033D01*
G01X1141832Y1027018D02*
X1161743Y1022976D01*
G01X1141943Y1028118D02*
X1191621Y1018033D01*
G01X1141943Y1028118D02*
X1191621Y1018033D01*
G01X1172562Y1020779D02*
X1191217Y1016992D01*
G01X1168466Y1021611D02*
X1169936Y1021312D01*
G01X1164369Y1022442D02*
X1165839Y1022144D01*
G01X1141832Y1027018D02*
X1161743Y1022976D01*
G01X1169491Y1027819D02*
X1192557Y1023136D01*
G01X1138643Y1035204D02*
X1192961Y1024177D01*
G01X1165394Y1028651D02*
X1166864Y1028352D01*
G01X1138643Y1035204D02*
X1192961Y1024177D01*
G01X1161298Y1029482D02*
X1162768Y1029184D01*
G01X1138643Y1035204D02*
X1192961Y1024177D01*
G01X1138532Y1034104D02*
X1158671Y1030015D01*
G01X1138643Y1035204D02*
X1192961Y1024177D01*
G01X1138643Y1035204D02*
X1192961Y1024177D01*
G01X1169491Y1027819D02*
X1192557Y1023136D01*
G01X1165394Y1028651D02*
X1166864Y1028352D01*
G01X1161298Y1029482D02*
X1162768Y1029184D01*
G01X1138532Y1034104D02*
X1158671Y1030015D01*
G01X1143825Y1041191D02*
X1189195Y1031983D01*
G01X1143936Y1042291D02*
X1189599Y1033024D01*
G01X1143936Y1042291D02*
X1189599Y1033024D01*
G01X1143825Y1041191D02*
X1189195Y1031983D01*
G01X1223808Y117081D02*
X1204940Y112895D01*
G01X1223808Y117081D02*
X1204940Y112895D01*
G01X1223695Y131703D02*
X1191379Y125016D01*
G01X1207315Y129439D02*
X1191374Y126139D01*
G01X1223690Y132826D02*
X1207315Y129439D01*
G01X1310306Y114525D02*
X1223695Y131703D01*
G01X1310301Y115648D02*
X1223690Y132826D01*
G01X1207315Y129439D02*
X1191374Y126139D01*
G01X1223695Y131703D02*
X1191379Y125016D01*
G01X1223690Y132826D02*
X1207315Y129439D01*
G01X1223695Y131703D02*
X1191379Y125016D01*
G01X1310301Y115648D02*
X1223690Y132826D01*
G01X1310306Y114525D02*
X1223695Y131703D01*
G01X1242677Y121267D02*
X1223808Y117081D01*
G01X1242677Y121267D02*
X1223808Y117081D01*
G01X1203923Y928745D02*
X1203106Y927487D01*
G01X1206200Y932250D02*
X1205383Y930992D01*
G01X1210451Y938797D02*
X1207659Y934498D01*
G01X1203923Y928745D02*
X1203106Y927487D01*
G01X1206200Y932250D02*
X1205383Y930992D01*
G01X1210451Y938797D02*
X1207659Y934498D01*
G01X1221436Y964772D02*
X1214801Y934837D01*
G01X1222562Y964767D02*
X1215833Y934404D01*
G01X1222562Y964767D02*
X1215833Y934404D01*
G01X1221436Y964772D02*
X1214801Y934837D01*
G01X1210986Y919391D02*
X1210169Y918133D01*
G01X1213219Y922829D02*
X1212402Y921571D01*
G01X1218900Y931576D02*
X1214635Y925010D01*
G01X1226244Y964712D02*
X1218900Y931576D01*
G01X1227370Y964708D02*
X1219933Y931146D01*
G01X1210986Y919391D02*
X1210169Y918133D01*
G01X1213219Y922829D02*
X1212402Y921571D01*
G01X1218900Y931576D02*
X1214635Y925010D01*
G01X1227370Y964708D02*
X1219933Y931146D01*
G01X1226244Y964712D02*
X1218900Y931576D01*
G01X1215406Y914115D02*
X1214589Y912857D01*
G01X1217683Y917621D02*
X1216866Y916363D01*
G01X1220615Y922136D02*
X1219143Y919869D01*
G01X1231204Y969910D02*
X1220615Y922136D01*
G01X1232330Y969905D02*
X1221647Y921702D01*
G01X1215406Y914115D02*
X1214589Y912857D01*
G01X1217683Y917621D02*
X1216866Y916363D01*
G01X1220615Y922136D02*
X1219143Y919869D01*
G01X1232330Y969905D02*
X1221647Y921702D01*
G01X1231204Y969910D02*
X1220615Y922136D01*
G01X1217258Y964429D02*
X1211483Y938364D01*
G01X1216132Y964434D02*
X1210451Y938797D01*
G01X1210987Y993918D02*
X1217258Y964429D01*
G01X1209953Y993490D02*
X1216132Y964434D01*
G01D02*
X1210451Y938797D01*
G01X1217258Y964429D02*
X1211483Y938364D01*
G01X1209953Y993490D02*
X1216132Y964434D01*
G01X1210987Y993918D02*
X1217258Y964429D01*
G01X1219887Y972053D02*
X1221436Y964772D01*
G01X1215568Y997655D02*
X1222562Y964767D01*
G01X1219018Y976142D02*
X1219330Y974675D01*
G01X1215568Y997655D02*
X1222562Y964767D01*
G01X1218148Y980231D02*
X1218460Y978763D01*
G01X1215568Y997655D02*
X1222562Y964767D01*
G01X1214534Y997227D02*
X1217591Y982852D01*
G01X1215568Y997655D02*
X1222562Y964767D01*
G01X1215568Y997655D02*
X1222562Y964767D01*
G01X1219887Y972053D02*
X1221436Y964772D01*
G01X1219018Y976142D02*
X1219330Y974675D01*
G01X1218148Y980231D02*
X1218460Y978763D01*
G01X1214534Y997227D02*
X1217591Y982852D01*
G01X1218133Y1002858D02*
X1226244Y964712D01*
G01X1219167Y1003286D02*
X1227370Y964708D01*
G01X1219167Y1003286D02*
X1227370Y964708D01*
G01X1218133Y1002858D02*
X1226244Y964712D01*
G01X1223805Y1004719D02*
X1231204Y969910D01*
G01X1224839Y1005147D02*
X1232330Y969907D01*
G01X1224839Y1005147D02*
X1232330Y969907D01*
G01X1223805Y1004719D02*
X1231204Y969910D01*
G01X1204714Y1003579D02*
X1210987Y993918D01*
G01X1203930Y1002766D02*
X1209953Y993490D01*
G01X1192361Y1010980D02*
X1204714Y1003579D01*
G01X1191957Y1009939D02*
X1203930Y1002766D01*
G01D02*
X1209953Y993490D01*
G01X1204714Y1003579D02*
X1210987Y993918D01*
G01X1191957Y1009939D02*
X1203930Y1002766D01*
G01X1192361Y1010980D02*
X1204714Y1003579D01*
G01X1208375Y1006710D02*
X1214534Y997227D01*
G01X1209159Y1007523D02*
X1215568Y997655D01*
G01X1191217Y1016992D02*
X1208375Y1006710D01*
G01X1200361Y1012795D02*
X1209159Y1007523D01*
G01X1191621Y1018033D02*
X1200361Y1012795D01*
G01X1209159Y1007523D02*
X1215568Y997655D01*
G01X1208375Y1006710D02*
X1214534Y997227D01*
G01X1200361Y1012795D02*
X1209159Y1007523D01*
G01X1191217Y1016992D02*
X1208375Y1006710D01*
G01X1191621Y1018033D02*
X1200361Y1012795D01*
G01X1191217Y1016992D02*
X1208375Y1006710D01*
G01X1212884Y1010955D02*
X1218133Y1002858D01*
G01X1213669Y1011768D02*
X1219167Y1003286D01*
G01X1192557Y1023136D02*
X1212884Y1010955D01*
G01X1192961Y1024177D02*
X1213669Y1011768D01*
G01D02*
X1219167Y1003286D01*
G01X1212884Y1010955D02*
X1218133Y1002858D01*
G01X1192961Y1024177D02*
X1213669Y1011768D01*
G01X1192557Y1023136D02*
X1212884Y1010955D01*
G01X1216869Y1015399D02*
X1223805Y1004719D01*
G01X1217653Y1016212D02*
X1224839Y1005147D01*
G01X1189195Y1031983D02*
X1216869Y1015399D01*
G01X1189599Y1033024D02*
X1217653Y1016212D01*
G01D02*
X1224839Y1005147D01*
G01X1216869Y1015399D02*
X1223805Y1004719D01*
G01X1189599Y1033024D02*
X1217653Y1016212D01*
G01X1189195Y1031983D02*
X1216869Y1015399D01*
G01X1308250Y108356D02*
X1242677Y121267D01*
G01X1308245Y109479D02*
X1242664Y122391D01*
G01X1308245Y109479D02*
X1242664Y122391D01*
G01X1308250Y108356D02*
X1242677Y121267D01*
G01X1432753Y139860D02*
X1310306Y114525D01*
G01X1340805Y121960D02*
X1310301Y115648D01*
G01X1340805Y121960D02*
X1310301Y115648D01*
G01X1432753Y139860D02*
X1310306Y114525D01*
G01X1432753Y139860D02*
X1310306Y114525D01*
G01X1417121Y130811D02*
X1308250Y108356D01*
G01X1417128Y131936D02*
X1308245Y109479D01*
G01X1417128Y131936D02*
X1308245Y109479D01*
G01X1417121Y130811D02*
X1308250Y108356D01*
G01X1432760Y140985D02*
X1340805Y121960D01*
G01X1432760Y140985D02*
X1340805Y121960D01*
G01X1437870Y126256D02*
X1417121Y130811D01*
G01X1438306Y127287D02*
X1417128Y131936D01*
G01X1438306Y127287D02*
X1417128Y131936D01*
G01X1437870Y126256D02*
X1417121Y130811D01*
G01X1496653Y125790D02*
X1432753Y139860D01*
G01X1497085Y126822D02*
X1432760Y140985D01*
G01X1497085Y126822D02*
X1432760Y140985D01*
G01X1496653Y125790D02*
X1432753Y139860D01*
G01X1442864Y122955D02*
X1437870Y126256D01*
G01X1443652Y123754D02*
X1438306Y127287D01*
G01X1443741Y121668D02*
X1442864Y122955D01*
G01X1444841Y122008D02*
X1443652Y123754D01*
G01X1443741Y118757D02*
Y121668D01*
G01X1444841Y118757D02*
Y122008D01*
G01X1445651Y116847D02*
G02X1443741Y118757I0J1910D01*
G01X1445651Y117947D02*
G02X1444841Y118757I0J810D01*
G01X1447335Y116847D02*
X1445651D01*
G01X1447335Y117947D02*
X1445651D01*
G01X1443652Y123754D02*
X1438306Y127287D01*
G01X1442864Y122955D02*
X1437870Y126256D01*
G01X1444841Y122008D02*
X1443652Y123754D01*
G01X1443741Y121668D02*
X1442864Y122955D01*
G01X1444841Y118757D02*
Y122008D01*
G01X1443741Y118757D02*
Y121668D01*
G01X1445651Y117947D02*
G02X1444841Y118757I0J810D01*
G01X1445651Y116847D02*
G02X1443741Y118757I0J1910D01*
G01X1447335Y117947D02*
X1445651D01*
G01X1447335Y116847D02*
X1445651D01*
G01X1498676Y124476D02*
X1496653Y125790D01*
G01X1499461Y125278D02*
X1497085Y126822D01*
G01X1500434Y121893D02*
X1498676Y124476D01*
G01X1501534Y122232D02*
X1499461Y125278D01*
G01X1500434Y118757D02*
Y121893D01*
G01X1501534Y118757D02*
Y122232D01*
G01X1502344Y116847D02*
G02X1500434Y118757I0J1910D01*
G01X1502344Y117947D02*
G02X1501534Y118757I0J810D01*
G01X1504028Y116847D02*
X1502344D01*
G01X1504028Y117947D02*
X1502344D01*
G01X1499461Y125278D02*
X1497085Y126822D01*
G01X1498676Y124476D02*
X1496653Y125790D01*
G01X1501534Y122232D02*
X1499461Y125278D01*
G01X1500434Y121893D02*
X1498676Y124476D01*
G01X1501534Y118757D02*
Y122232D01*
G01X1500434Y118757D02*
Y121893D01*
G01X1502344Y117947D02*
G02X1501534Y118757I0J810D01*
G01X1502344Y116847D02*
G02X1500434Y118757I0J1910D01*
G01X1504028Y117947D02*
X1502344D01*
G01X1504028Y116847D02*
X1502344D01*
G54D13*
G01X6250Y-185556D02*
Y-203056D01*
G01X1228Y-185556D02*
X11272D01*
G01X20038Y-203056D02*
Y-185556D01*
G01Y-194014D02*
X21130Y-192556D01*
X22222Y-191681D01*
X23968Y-191390D01*
X25278Y-191681D01*
X26807Y-192848D01*
X27462Y-194598D01*
Y-203056D01*
G01X41250Y-191390D02*
Y-203056D01*
G01Y-186723D02*
X40813Y-186431D01*
Y-185848D01*
X41250Y-185556D01*
X41687Y-185848D01*
Y-186431D01*
X41250Y-186723D01*
G01X55475Y-201015D02*
X56567Y-202181D01*
X58095Y-203056D01*
X59405D01*
X60715Y-202473D01*
X61588Y-201598D01*
X62025Y-200432D01*
X61807Y-198681D01*
X60933Y-197806D01*
X57003Y-196056D01*
X56130Y-194014D01*
X56567Y-192556D01*
X57440Y-191681D01*
X58750Y-191390D01*
X60060Y-191681D01*
X61370Y-192556D01*
G01X90693Y-207431D02*
X92222Y-208598D01*
X93968Y-208889D01*
X95496Y-208598D01*
X96807Y-207140D01*
X97680Y-205098D01*
Y-191390D01*
G01Y-193723D02*
X96807Y-192556D01*
X95496Y-191681D01*
X93968Y-191390D01*
X92222Y-191973D01*
X91130Y-193139D01*
X90256Y-195181D01*
X89820Y-197223D01*
X90038Y-198973D01*
X90912Y-201015D01*
X92222Y-202473D01*
X93968Y-203056D01*
X95278Y-202764D01*
X96807Y-201598D01*
X97680Y-200432D01*
G01X107975Y-195181D02*
X114962D01*
X114307Y-193139D01*
X113215Y-191973D01*
X111687Y-191390D01*
X110158Y-191681D01*
X108848Y-192556D01*
X107975Y-194598D01*
X107538Y-196348D01*
Y-198098D01*
X107975Y-199848D01*
X109067Y-201598D01*
X110377Y-202764D01*
X111905Y-203056D01*
X113433Y-202473D01*
X114962Y-200723D01*
G01X125693Y-203056D02*
Y-191390D01*
G01Y-193723D02*
X126785Y-192556D01*
X127877Y-191681D01*
X129405Y-191390D01*
X130496Y-191681D01*
X131807Y-192556D01*
G01X142320Y-203056D02*
Y-185556D01*
G01Y-194306D02*
X143412Y-192556D01*
X144722Y-191681D01*
X146032Y-191390D01*
X147996Y-191973D01*
X149307Y-193139D01*
X150180Y-195181D01*
Y-197514D01*
X149743Y-199848D01*
X148870Y-201598D01*
X147342Y-202764D01*
X146032Y-203056D01*
X144722Y-202764D01*
X143412Y-201890D01*
X142320Y-200432D01*
G01X160475Y-195181D02*
X167462D01*
X166807Y-193139D01*
X165715Y-191973D01*
X164187Y-191390D01*
X162658Y-191681D01*
X161348Y-192556D01*
X160475Y-194598D01*
X160038Y-196348D01*
Y-198098D01*
X160475Y-199848D01*
X161567Y-201598D01*
X162877Y-202764D01*
X164405Y-203056D01*
X165933Y-202473D01*
X167462Y-200723D01*
G01X178193Y-203056D02*
Y-191390D01*
G01Y-193723D02*
X179285Y-192556D01*
X180377Y-191681D01*
X181905Y-191390D01*
X182996Y-191681D01*
X184307Y-192556D01*
G01X216250Y-191390D02*
Y-203056D01*
G01Y-186723D02*
X215813Y-186431D01*
Y-185848D01*
X216250Y-185556D01*
X216687Y-185848D01*
Y-186431D01*
X216250Y-186723D01*
G01X230475Y-201015D02*
X231567Y-202181D01*
X233095Y-203056D01*
X234405D01*
X235715Y-202473D01*
X236588Y-201598D01*
X237025Y-200432D01*
X236807Y-198681D01*
X235933Y-197806D01*
X232003Y-196056D01*
X231130Y-194014D01*
X231567Y-192556D01*
X232440Y-191681D01*
X233750Y-191390D01*
X235060Y-191681D01*
X236370Y-192556D01*
G01X265256Y-207431D02*
X266785Y-208598D01*
X268095Y-208889D01*
X269842Y-208306D01*
X271152Y-206848D01*
X271807Y-204222D01*
Y-191390D01*
G01Y-186723D02*
X271370Y-186431D01*
Y-185848D01*
X271807Y-185556D01*
X272243Y-185848D01*
Y-186431D01*
X271807Y-186723D01*
G01X282538Y-191390D02*
Y-199556D01*
X283412Y-201598D01*
X284722Y-202764D01*
X286250Y-203056D01*
X287778Y-202764D01*
X289088Y-201598D01*
X289962Y-199556D01*
G01Y-203056D02*
Y-191390D01*
G01X300475Y-201015D02*
X301567Y-202181D01*
X303095Y-203056D01*
X304405D01*
X305715Y-202473D01*
X306588Y-201598D01*
X307025Y-200432D01*
X306807Y-198681D01*
X305933Y-197806D01*
X302003Y-196056D01*
X301130Y-194014D01*
X301567Y-192556D01*
X302440Y-191681D01*
X303750Y-191390D01*
X305060Y-191681D01*
X306370Y-192556D01*
G01X321250Y-185556D02*
Y-203056D01*
G01X318193Y-191390D02*
X324307D01*
G01X354940Y-203056D02*
Y-188181D01*
X355377Y-186723D01*
X356250Y-185848D01*
X357560Y-185556D01*
X358870Y-186139D01*
X359525Y-187598D01*
G01X356905Y-192556D02*
X352538D01*
G01X373750Y-203056D02*
X372440Y-202764D01*
X371130Y-201598D01*
X370256Y-199556D01*
X369820Y-197223D01*
X370256Y-194889D01*
X371130Y-192848D01*
X372440Y-191681D01*
X373750Y-191390D01*
X375060Y-191681D01*
X376370Y-192848D01*
X377243Y-194889D01*
X377462Y-197223D01*
X377243Y-199556D01*
X376370Y-201598D01*
X375060Y-202764D01*
X373750Y-203056D01*
G01X388193D02*
Y-191390D01*
G01Y-193723D02*
X389285Y-192556D01*
X390377Y-191681D01*
X391905Y-191390D01*
X392996Y-191681D01*
X394307Y-192556D01*
G01X421665Y-208306D02*
X422975Y-208889D01*
X424722Y-208306D01*
X425813Y-207140D01*
X426687Y-205681D01*
X427996Y-201015D01*
X430835Y-191390D01*
G01X423848D02*
X427996Y-201015D01*
G01X443750Y-203056D02*
X442440Y-202764D01*
X441130Y-201598D01*
X440256Y-199556D01*
X439820Y-197223D01*
X440256Y-194889D01*
X441130Y-192848D01*
X442440Y-191681D01*
X443750Y-191390D01*
X445060Y-191681D01*
X446370Y-192848D01*
X447243Y-194889D01*
X447462Y-197223D01*
X447243Y-199556D01*
X446370Y-201598D01*
X445060Y-202764D01*
X443750Y-203056D01*
G01X457538Y-191390D02*
Y-199556D01*
X458412Y-201598D01*
X459722Y-202764D01*
X461250Y-203056D01*
X462778Y-202764D01*
X464088Y-201598D01*
X464962Y-199556D01*
G01Y-203056D02*
Y-191390D01*
G01X475693Y-203056D02*
Y-191390D01*
G01Y-193723D02*
X476785Y-192556D01*
X477877Y-191681D01*
X479405Y-191390D01*
X480496Y-191681D01*
X481807Y-192556D01*
G01X510693Y-203056D02*
Y-191390D01*
G01Y-193723D02*
X511785Y-192556D01*
X512877Y-191681D01*
X514405Y-191390D01*
X515496Y-191681D01*
X516807Y-192556D01*
G01X527975Y-195181D02*
X534962D01*
X534307Y-193139D01*
X533215Y-191973D01*
X531687Y-191390D01*
X530158Y-191681D01*
X528848Y-192556D01*
X527975Y-194598D01*
X527538Y-196348D01*
Y-198098D01*
X527975Y-199848D01*
X529067Y-201598D01*
X530377Y-202764D01*
X531905Y-203056D01*
X533433Y-202473D01*
X534962Y-200723D01*
G01X547440Y-203056D02*
Y-188181D01*
X547877Y-186723D01*
X548750Y-185848D01*
X550060Y-185556D01*
X551370Y-186139D01*
X552025Y-187598D01*
G01X549405Y-192556D02*
X545038D01*
G01X562975Y-195181D02*
X569962D01*
X569307Y-193139D01*
X568215Y-191973D01*
X566687Y-191390D01*
X565158Y-191681D01*
X563848Y-192556D01*
X562975Y-194598D01*
X562538Y-196348D01*
Y-198098D01*
X562975Y-199848D01*
X564067Y-201598D01*
X565377Y-202764D01*
X566905Y-203056D01*
X568433Y-202473D01*
X569962Y-200723D01*
G01X580693Y-203056D02*
Y-191390D01*
G01Y-193723D02*
X581785Y-192556D01*
X582877Y-191681D01*
X584405Y-191390D01*
X585496Y-191681D01*
X586807Y-192556D01*
G01X597975Y-195181D02*
X604962D01*
X604307Y-193139D01*
X603215Y-191973D01*
X601687Y-191390D01*
X600158Y-191681D01*
X598848Y-192556D01*
X597975Y-194598D01*
X597538Y-196348D01*
Y-198098D01*
X597975Y-199848D01*
X599067Y-201598D01*
X600377Y-202764D01*
X601905Y-203056D01*
X603433Y-202473D01*
X604962Y-200723D01*
G01X615038Y-203056D02*
Y-191390D01*
G01Y-194306D02*
X615912Y-192848D01*
X617222Y-191681D01*
X618968Y-191390D01*
X620496Y-191681D01*
X621807Y-192848D01*
X622462Y-194889D01*
Y-203056D01*
G01X639743Y-192848D02*
X638215Y-191681D01*
X636905Y-191390D01*
X635158Y-191973D01*
X633848Y-193139D01*
X632975Y-195181D01*
X632756Y-197223D01*
X632975Y-199265D01*
X633848Y-201015D01*
X635158Y-202473D01*
X636905Y-203056D01*
X638433Y-202473D01*
X639743Y-201306D01*
G01X650475Y-195181D02*
X657462D01*
X656807Y-193139D01*
X655715Y-191973D01*
X654187Y-191390D01*
X652658Y-191681D01*
X651348Y-192556D01*
X650475Y-194598D01*
X650038Y-196348D01*
Y-198098D01*
X650475Y-199848D01*
X651567Y-201598D01*
X652877Y-202764D01*
X654405Y-203056D01*
X655933Y-202473D01*
X657462Y-200723D01*
G01X688750Y-185556D02*
Y-203056D01*
G01X685693Y-191390D02*
X691807D01*
G01X706250Y-203056D02*
X704940Y-202764D01*
X703630Y-201598D01*
X702756Y-199556D01*
X702320Y-197223D01*
X702756Y-194889D01*
X703630Y-192848D01*
X704940Y-191681D01*
X706250Y-191390D01*
X707560Y-191681D01*
X708870Y-192848D01*
X709743Y-194889D01*
X709962Y-197223D01*
X709743Y-199556D01*
X708870Y-201598D01*
X707560Y-202764D01*
X706250Y-203056D01*
G01X739940D02*
Y-188181D01*
X740377Y-186723D01*
X741250Y-185848D01*
X742560Y-185556D01*
X743870Y-186139D01*
X744525Y-187598D01*
G01X741905Y-192556D02*
X737538D01*
G01X758750Y-191390D02*
Y-203056D01*
G01Y-186723D02*
X758313Y-186431D01*
Y-185848D01*
X758750Y-185556D01*
X759187Y-185848D01*
Y-186431D01*
X758750Y-186723D01*
G01X772538Y-203056D02*
Y-191390D01*
G01Y-194306D02*
X773412Y-192848D01*
X774722Y-191681D01*
X776468Y-191390D01*
X777996Y-191681D01*
X779307Y-192848D01*
X779962Y-194889D01*
Y-203056D01*
G01X797680Y-185556D02*
Y-203056D01*
G01Y-200432D02*
X796807Y-201890D01*
X795496Y-202764D01*
X793968Y-203056D01*
X792222Y-202473D01*
X790912Y-201015D01*
X790038Y-199265D01*
X789820Y-197223D01*
X790038Y-195181D01*
X790912Y-193431D01*
X792222Y-191973D01*
X793968Y-191390D01*
X795496Y-191681D01*
X796588Y-192265D01*
X797680Y-193431D01*
G01X828750Y-185556D02*
Y-203056D01*
G01X825693Y-191390D02*
X831807D01*
G01X842538Y-203056D02*
Y-185556D01*
G01Y-194014D02*
X843630Y-192556D01*
X844722Y-191681D01*
X846468Y-191390D01*
X847778Y-191681D01*
X849307Y-192848D01*
X849962Y-194598D01*
Y-203056D01*
G01X860475Y-195181D02*
X867462D01*
X866807Y-193139D01*
X865715Y-191973D01*
X864187Y-191390D01*
X862658Y-191681D01*
X861348Y-192556D01*
X860475Y-194598D01*
X860038Y-196348D01*
Y-198098D01*
X860475Y-199848D01*
X861567Y-201598D01*
X862877Y-202764D01*
X864405Y-203056D01*
X865933Y-202473D01*
X867462Y-200723D01*
G01X893947Y-203056D02*
Y-185556D01*
X898313D01*
X900060Y-186431D01*
X901370Y-187598D01*
X902462Y-189347D01*
X903335Y-191390D01*
X903553Y-194306D01*
X903335Y-197223D01*
X902462Y-199265D01*
X901370Y-201015D01*
X900060Y-202181D01*
X898313Y-203056D01*
X893947D01*
G01X911883D02*
Y-185556D01*
X917123D01*
X918870Y-186431D01*
X920180Y-188473D01*
X920617Y-190806D01*
X920180Y-193139D01*
X919088Y-194889D01*
X917123Y-195765D01*
X911883D01*
G01X951250Y-191390D02*
Y-203056D01*
G01Y-186723D02*
X950813Y-186431D01*
Y-185848D01*
X951250Y-185556D01*
X951687Y-185848D01*
Y-186431D01*
X951250Y-186723D01*
G01X962200Y-203056D02*
Y-191390D01*
G01Y-194598D02*
X962855Y-193139D01*
X963947Y-191973D01*
X965475Y-191390D01*
X967003Y-191973D01*
X968095Y-193139D01*
X968750Y-194598D01*
Y-203056D01*
G01Y-194598D02*
X969405Y-193139D01*
X970496Y-191973D01*
X972025Y-191390D01*
X973553Y-191973D01*
X974645Y-193139D01*
X975300Y-194889D01*
Y-203056D01*
G01X982320Y-208889D02*
Y-191390D01*
G01Y-194014D02*
X983412Y-192556D01*
X984503Y-191681D01*
X986250Y-191390D01*
X987778Y-191681D01*
X989307Y-193139D01*
X989962Y-195181D01*
X990180Y-197223D01*
X989962Y-199265D01*
X989307Y-201306D01*
X987996Y-202473D01*
X986250Y-203056D01*
X984722Y-202764D01*
X983193Y-201890D01*
X982320Y-200723D01*
G01X1000475Y-195181D02*
X1007462D01*
X1006807Y-193139D01*
X1005715Y-191973D01*
X1004187Y-191390D01*
X1002658Y-191681D01*
X1001348Y-192556D01*
X1000475Y-194598D01*
X1000038Y-196348D01*
Y-198098D01*
X1000475Y-199848D01*
X1001567Y-201598D01*
X1002877Y-202764D01*
X1004405Y-203056D01*
X1005933Y-202473D01*
X1007462Y-200723D01*
G01X1025180Y-185556D02*
Y-203056D01*
G01Y-200432D02*
X1024307Y-201890D01*
X1022996Y-202764D01*
X1021468Y-203056D01*
X1019722Y-202473D01*
X1018412Y-201015D01*
X1017538Y-199265D01*
X1017320Y-197223D01*
X1017538Y-195181D01*
X1018412Y-193431D01*
X1019722Y-191973D01*
X1021468Y-191390D01*
X1022996Y-191681D01*
X1024088Y-192265D01*
X1025180Y-193431D01*
G01X1042680Y-203056D02*
Y-191390D01*
G01Y-193431D02*
X1041807Y-192265D01*
X1040496Y-191681D01*
X1038968Y-191390D01*
X1037440Y-191973D01*
X1036130Y-193139D01*
X1035256Y-194889D01*
X1034820Y-197223D01*
X1035256Y-199556D01*
X1036130Y-201306D01*
X1037440Y-202473D01*
X1038968Y-203056D01*
X1040496Y-202764D01*
X1041807Y-201890D01*
X1042680Y-200723D01*
G01X1052538Y-203056D02*
Y-191390D01*
G01Y-194306D02*
X1053412Y-192848D01*
X1054722Y-191681D01*
X1056468Y-191390D01*
X1057996Y-191681D01*
X1059307Y-192848D01*
X1059962Y-194889D01*
Y-203056D01*
G01X1077243Y-192848D02*
X1075715Y-191681D01*
X1074405Y-191390D01*
X1072658Y-191973D01*
X1071348Y-193139D01*
X1070475Y-195181D01*
X1070256Y-197223D01*
X1070475Y-199265D01*
X1071348Y-201015D01*
X1072658Y-202473D01*
X1074405Y-203056D01*
X1075933Y-202473D01*
X1077243Y-201306D01*
G01X1087975Y-195181D02*
X1094962D01*
X1094307Y-193139D01*
X1093215Y-191973D01*
X1091687Y-191390D01*
X1090158Y-191681D01*
X1088848Y-192556D01*
X1087975Y-194598D01*
X1087538Y-196348D01*
Y-198098D01*
X1087975Y-199848D01*
X1089067Y-201598D01*
X1090377Y-202764D01*
X1091905Y-203056D01*
X1093433Y-202473D01*
X1094962Y-200723D01*
G01X1126250Y-185556D02*
Y-203056D01*
G01X1123193Y-191390D02*
X1129307D01*
G01X1140693Y-203056D02*
Y-191390D01*
G01Y-193723D02*
X1141785Y-192556D01*
X1142877Y-191681D01*
X1144405Y-191390D01*
X1145496Y-191681D01*
X1146807Y-192556D01*
G01X1165180Y-203056D02*
Y-191390D01*
G01Y-193431D02*
X1164307Y-192265D01*
X1162996Y-191681D01*
X1161468Y-191390D01*
X1159940Y-191973D01*
X1158630Y-193139D01*
X1157756Y-194889D01*
X1157320Y-197223D01*
X1157756Y-199556D01*
X1158630Y-201306D01*
X1159940Y-202473D01*
X1161468Y-203056D01*
X1162996Y-202764D01*
X1164307Y-201890D01*
X1165180Y-200723D01*
G01X1182243Y-192848D02*
X1180715Y-191681D01*
X1179405Y-191390D01*
X1177658Y-191973D01*
X1176348Y-193139D01*
X1175475Y-195181D01*
X1175256Y-197223D01*
X1175475Y-199265D01*
X1176348Y-201015D01*
X1177658Y-202473D01*
X1179405Y-203056D01*
X1180933Y-202473D01*
X1182243Y-201306D01*
G01X1192975Y-195181D02*
X1199962D01*
X1199307Y-193139D01*
X1198215Y-191973D01*
X1196687Y-191390D01*
X1195158Y-191681D01*
X1193848Y-192556D01*
X1192975Y-194598D01*
X1192538Y-196348D01*
Y-198098D01*
X1192975Y-199848D01*
X1194067Y-201598D01*
X1195377Y-202764D01*
X1196905Y-203056D01*
X1198433Y-202473D01*
X1199962Y-200723D01*
G01X1210475Y-201015D02*
X1211567Y-202181D01*
X1213095Y-203056D01*
X1214405D01*
X1215715Y-202473D01*
X1216588Y-201598D01*
X1217025Y-200432D01*
X1216807Y-198681D01*
X1215933Y-197806D01*
X1212003Y-196056D01*
X1211130Y-194014D01*
X1211567Y-192556D01*
X1212440Y-191681D01*
X1213750Y-191390D01*
X1215060Y-191681D01*
X1216370Y-192556D01*
G01X1248750Y-191390D02*
Y-203056D01*
G01Y-186723D02*
X1248313Y-186431D01*
Y-185848D01*
X1248750Y-185556D01*
X1249187Y-185848D01*
Y-186431D01*
X1248750Y-186723D01*
G01X1262538Y-203056D02*
Y-191390D01*
G01Y-194306D02*
X1263412Y-192848D01*
X1264722Y-191681D01*
X1266468Y-191390D01*
X1267996Y-191681D01*
X1269307Y-192848D01*
X1269962Y-194889D01*
Y-203056D01*
G01X1301250D02*
Y-185556D01*
G01X1322680Y-203056D02*
Y-191390D01*
G01Y-193431D02*
X1321807Y-192265D01*
X1320496Y-191681D01*
X1318968Y-191390D01*
X1317440Y-191973D01*
X1316130Y-193139D01*
X1315256Y-194889D01*
X1314820Y-197223D01*
X1315256Y-199556D01*
X1316130Y-201306D01*
X1317440Y-202473D01*
X1318968Y-203056D01*
X1320496Y-202764D01*
X1321807Y-201890D01*
X1322680Y-200723D01*
G01X1331665Y-208306D02*
X1332975Y-208889D01*
X1334722Y-208306D01*
X1335813Y-207140D01*
X1336687Y-205681D01*
X1337996Y-201015D01*
X1340835Y-191390D01*
G01X1333848D02*
X1337996Y-201015D01*
G01X1350475Y-195181D02*
X1357462D01*
X1356807Y-193139D01*
X1355715Y-191973D01*
X1354187Y-191390D01*
X1352658Y-191681D01*
X1351348Y-192556D01*
X1350475Y-194598D01*
X1350038Y-196348D01*
Y-198098D01*
X1350475Y-199848D01*
X1351567Y-201598D01*
X1352877Y-202764D01*
X1354405Y-203056D01*
X1355933Y-202473D01*
X1357462Y-200723D01*
G01X1368193Y-203056D02*
Y-191390D01*
G01Y-193723D02*
X1369285Y-192556D01*
X1370377Y-191681D01*
X1371905Y-191390D01*
X1372996Y-191681D01*
X1374307Y-192556D01*
G01X1401883Y-185556D02*
Y-203056D01*
X1410617D01*
G01X1423750D02*
X1425278Y-202764D01*
X1427025Y-201890D01*
X1428117Y-200432D01*
X1428553Y-198389D01*
X1428117Y-196348D01*
X1426807Y-194598D01*
X1424842Y-193723D01*
X1422658D01*
X1421348Y-193139D01*
X1420256Y-191681D01*
X1419820Y-189640D01*
X1420475Y-187598D01*
X1422003Y-186139D01*
X1423750Y-185556D01*
X1425496Y-186139D01*
X1427025Y-187598D01*
X1427680Y-189640D01*
X1427243Y-191681D01*
X1426152Y-193139D01*
X1424842Y-193723D01*
X1422658D01*
X1420693Y-194598D01*
X1419383Y-196348D01*
X1418947Y-198389D01*
X1419383Y-200432D01*
X1420475Y-201890D01*
X1422222Y-202764D01*
X1423750Y-203056D01*
G01X1441250Y-203639D02*
X1440813Y-203348D01*
Y-202764D01*
X1441250Y-202473D01*
X1441687Y-202764D01*
Y-203348D01*
X1441250Y-203639D01*
G01X2008773Y1616518D02*
X2014013D01*
G01X2011393D02*
Y1599018D01*
G01X2008773D02*
X2014013D01*
G01X2023216D02*
Y1616518D01*
X2028893Y1601935D01*
X2034570Y1616518D01*
Y1599018D01*
G01X2042026D02*
Y1616518D01*
X2047266D01*
X2049013Y1615643D01*
X2050323Y1613601D01*
X2050760Y1611268D01*
X2050323Y1608935D01*
X2049231Y1607185D01*
X2047266Y1606309D01*
X2042026D01*
G01X2062801Y1593185D02*
X2060618Y1596101D01*
X2059526Y1599018D01*
Y1610684D01*
X2060618Y1613601D01*
X2062801Y1616518D01*
G01X2081393Y1599018D02*
X2079646Y1599310D01*
X2078118Y1600476D01*
X2076808Y1602226D01*
X2075934Y1604268D01*
X2075498Y1606601D01*
Y1608935D01*
X2075934Y1611268D01*
X2076808Y1613310D01*
X2078118Y1615059D01*
X2079646Y1616226D01*
X2081393Y1616518D01*
X2083139Y1616226D01*
X2084668Y1615059D01*
X2085978Y1613310D01*
X2086852Y1611268D01*
X2087288Y1608935D01*
Y1606601D01*
X2086852Y1604268D01*
X2085978Y1602226D01*
X2084668Y1600476D01*
X2083139Y1599310D01*
X2081393Y1599018D01*
G01X2095181D02*
Y1616518D01*
G01Y1608060D02*
X2096273Y1609518D01*
X2097365Y1610393D01*
X2099111Y1610684D01*
X2100421Y1610393D01*
X2101950Y1609226D01*
X2102605Y1607476D01*
Y1599018D01*
G01X2109843D02*
Y1610684D01*
G01Y1607476D02*
X2110498Y1608935D01*
X2111590Y1610101D01*
X2113118Y1610684D01*
X2114646Y1610101D01*
X2115738Y1608935D01*
X2116393Y1607476D01*
Y1599018D01*
G01Y1607476D02*
X2117048Y1608935D01*
X2118139Y1610101D01*
X2119668Y1610684D01*
X2121196Y1610101D01*
X2122288Y1608935D01*
X2122943Y1607185D01*
Y1599018D01*
G01X2134985Y1593185D02*
X2137168Y1596101D01*
X2138260Y1599018D01*
Y1610684D01*
X2137168Y1613601D01*
X2134985Y1616518D01*
G01X1986890Y1633668D02*
Y1651168D01*
X1991256D01*
X1993003Y1650293D01*
X1994313Y1649126D01*
X1995405Y1647377D01*
X1996278Y1645334D01*
X1996496Y1642418D01*
X1996278Y1639501D01*
X1995405Y1637459D01*
X1994313Y1635709D01*
X1993003Y1634543D01*
X1991256Y1633668D01*
X1986890D01*
G01X2004826D02*
Y1651168D01*
X2010066D01*
X2011813Y1650293D01*
X2013123Y1648251D01*
X2013560Y1645918D01*
X2013123Y1643585D01*
X2012031Y1641835D01*
X2010066Y1640959D01*
X2004826D01*
G01X2041573Y1651168D02*
X2046813D01*
G01X2044193D02*
Y1633668D01*
G01X2041573D02*
X2046813D01*
G01X2056016D02*
Y1651168D01*
X2061693Y1636585D01*
X2067370Y1651168D01*
Y1633668D01*
G01X2074826D02*
Y1651168D01*
X2080066D01*
X2081813Y1650293D01*
X2083123Y1648251D01*
X2083560Y1645918D01*
X2083123Y1643585D01*
X2082031Y1641835D01*
X2080066Y1640959D01*
X2074826D01*
G01X2101060Y1633668D02*
X2092326D01*
Y1651168D01*
X2101060D01*
G01X2097566Y1642710D02*
X2092326D01*
G01X2109390Y1633668D02*
Y1651168D01*
X2113756D01*
X2115503Y1650293D01*
X2116813Y1649126D01*
X2117905Y1647377D01*
X2118778Y1645334D01*
X2118996Y1642418D01*
X2118778Y1639501D01*
X2117905Y1637459D01*
X2116813Y1635709D01*
X2115503Y1634543D01*
X2113756Y1633668D01*
X2109390D01*
G01X2126234D02*
X2131693Y1651168D01*
X2137152Y1633668D01*
G01X2135186Y1639793D02*
X2128199D01*
G01X2144171Y1633668D02*
Y1651168D01*
X2154215Y1633668D01*
Y1651168D01*
G01X2171496Y1649709D02*
X2170186Y1650585D01*
X2168658Y1651168D01*
X2166911D01*
X2164946Y1650293D01*
X2163418Y1648835D01*
X2162326Y1647084D01*
X2161453Y1644168D01*
X2161234Y1641543D01*
X2161671Y1638918D01*
X2162326Y1637168D01*
X2163636Y1635418D01*
X2165165Y1634251D01*
X2166693Y1633668D01*
X2168221D01*
X2169750Y1634251D01*
X2171060Y1635126D01*
X2172152Y1636292D01*
G01X2188560Y1633668D02*
X2179826D01*
Y1651168D01*
X2188560D01*
G01X2185066Y1642710D02*
X2179826D01*
G01X2219193Y1651168D02*
Y1633668D01*
G01X2214171Y1651168D02*
X2224215D01*
G01X2231234Y1633668D02*
X2236693Y1651168D01*
X2242152Y1633668D01*
G01X2240186Y1639793D02*
X2233199D01*
G01X2255939Y1643001D02*
X2256813Y1643876D01*
X2257468Y1645334D01*
X2257905Y1647377D01*
X2257468Y1649126D01*
X2256595Y1650293D01*
X2255066Y1651168D01*
X2249171D01*
Y1633668D01*
X2256376D01*
X2257905Y1634834D01*
X2258778Y1636585D01*
X2259215Y1638626D01*
X2258778Y1640668D01*
X2257468Y1642418D01*
X2255939Y1643001D01*
X2249171D01*
G01X2267326Y1651168D02*
Y1633668D01*
X2276060D01*
G01X2293560D02*
X2284826D01*
Y1651168D01*
X2293560D01*
G01X2290066Y1642710D02*
X2284826D01*
G01X2306693Y1633085D02*
X2306256Y1633376D01*
Y1633960D01*
X2306693Y1634251D01*
X2307130Y1633960D01*
Y1633376D01*
X2306693Y1633085D01*
G01Y1640959D02*
X2306256Y1641251D01*
Y1641835D01*
X2306693Y1642126D01*
X2307130Y1641835D01*
Y1641251D01*
X2306693Y1640959D01*
G01X2337326Y1651168D02*
Y1633668D01*
X2346060D01*
G01X2359193D02*
X2360721Y1633960D01*
X2362468Y1634834D01*
X2363560Y1636292D01*
X2363996Y1638335D01*
X2363560Y1640376D01*
X2362250Y1642126D01*
X2360285Y1643001D01*
X2358101D01*
X2356791Y1643585D01*
X2355699Y1645043D01*
X2355263Y1647084D01*
X2355918Y1649126D01*
X2357446Y1650585D01*
X2359193Y1651168D01*
X2360939Y1650585D01*
X2362468Y1649126D01*
X2363123Y1647084D01*
X2362686Y1645043D01*
X2361595Y1643585D01*
X2360285Y1643001D01*
X2358101D01*
X2356136Y1642126D01*
X2354826Y1640376D01*
X2354390Y1638335D01*
X2354826Y1636292D01*
X2355918Y1634834D01*
X2357665Y1633960D01*
X2359193Y1633668D01*
G01X2046393Y1564368D02*
X2047921Y1564660D01*
X2049668Y1565534D01*
X2050760Y1566992D01*
X2051196Y1569035D01*
X2050760Y1571076D01*
X2049450Y1572826D01*
X2047485Y1573701D01*
X2045301D01*
X2043991Y1574285D01*
X2042899Y1575743D01*
X2042463Y1577784D01*
X2043118Y1579826D01*
X2044646Y1581285D01*
X2046393Y1581868D01*
X2048139Y1581285D01*
X2049668Y1579826D01*
X2050323Y1577784D01*
X2049886Y1575743D01*
X2048795Y1574285D01*
X2047485Y1573701D01*
X2045301D01*
X2043336Y1572826D01*
X2042026Y1571076D01*
X2041590Y1569035D01*
X2042026Y1566992D01*
X2043118Y1565534D01*
X2044865Y1564660D01*
X2046393Y1564368D01*
G01X2059090Y1566992D02*
X2060399Y1565534D01*
X2061928Y1564660D01*
X2063893Y1564368D01*
X2065858Y1564951D01*
X2067386Y1566118D01*
X2068478Y1568159D01*
X2068696Y1570493D01*
X2068260Y1572826D01*
X2067168Y1574285D01*
X2065639Y1575451D01*
X2064111Y1575743D01*
X2062583Y1575451D01*
X2060618Y1574285D01*
X2061273Y1581868D01*
X2067168D01*
G01X2081393Y1563785D02*
X2080956Y1564076D01*
Y1564660D01*
X2081393Y1564951D01*
X2081830Y1564660D01*
Y1564076D01*
X2081393Y1563785D01*
G01X2098893Y1581868D02*
X2097146Y1581285D01*
X2095836Y1579826D01*
X2094963Y1578077D01*
X2094308Y1575743D01*
X2094090Y1573118D01*
X2094308Y1570493D01*
X2094963Y1568159D01*
X2095836Y1566409D01*
X2097146Y1564951D01*
X2098893Y1564368D01*
X2100639Y1564951D01*
X2101950Y1566409D01*
X2102823Y1568159D01*
X2103478Y1570493D01*
X2103696Y1573118D01*
X2103478Y1575743D01*
X2102823Y1578077D01*
X2101950Y1579826D01*
X2100639Y1581285D01*
X2098893Y1581868D01*
G01X2037643Y1529718D02*
Y1547218D01*
X2035023Y1543718D01*
G01Y1529718D02*
X2040263D01*
G01X2055143Y1547218D02*
X2053396Y1546635D01*
X2052086Y1545176D01*
X2051213Y1543427D01*
X2050558Y1541093D01*
X2050340Y1538468D01*
X2050558Y1535843D01*
X2051213Y1533509D01*
X2052086Y1531759D01*
X2053396Y1530301D01*
X2055143Y1529718D01*
X2056889Y1530301D01*
X2058200Y1531759D01*
X2059073Y1533509D01*
X2059728Y1535843D01*
X2059946Y1538468D01*
X2059728Y1541093D01*
X2059073Y1543427D01*
X2058200Y1545176D01*
X2056889Y1546635D01*
X2055143Y1547218D01*
G01X2072643D02*
X2070896Y1546635D01*
X2069586Y1545176D01*
X2068713Y1543427D01*
X2068058Y1541093D01*
X2067840Y1538468D01*
X2068058Y1535843D01*
X2068713Y1533509D01*
X2069586Y1531759D01*
X2070896Y1530301D01*
X2072643Y1529718D01*
X2074389Y1530301D01*
X2075700Y1531759D01*
X2076573Y1533509D01*
X2077228Y1535843D01*
X2077446Y1538468D01*
X2077228Y1541093D01*
X2076573Y1543427D01*
X2075700Y1545176D01*
X2074389Y1546635D01*
X2072643Y1547218D01*
G01X2090143Y1529135D02*
X2089706Y1529426D01*
Y1530010D01*
X2090143Y1530301D01*
X2090580Y1530010D01*
Y1529426D01*
X2090143Y1529135D01*
G01X2107643Y1547218D02*
X2105896Y1546635D01*
X2104586Y1545176D01*
X2103713Y1543427D01*
X2103058Y1541093D01*
X2102840Y1538468D01*
X2103058Y1535843D01*
X2103713Y1533509D01*
X2104586Y1531759D01*
X2105896Y1530301D01*
X2107643Y1529718D01*
X2109389Y1530301D01*
X2110700Y1531759D01*
X2111573Y1533509D01*
X2112228Y1535843D01*
X2112446Y1538468D01*
X2112228Y1541093D01*
X2111573Y1543427D01*
X2110700Y1545176D01*
X2109389Y1546635D01*
X2107643Y1547218D01*
G01X2214843Y1616518D02*
X2217899Y1599018D01*
X2221393Y1616518D01*
X2224886Y1599018D01*
X2227943Y1616518D01*
G01X2236273D02*
X2241513D01*
G01X2238893D02*
Y1599018D01*
G01X2236273D02*
X2241513D01*
G01X2251590D02*
Y1616518D01*
X2255956D01*
X2257703Y1615643D01*
X2259013Y1614476D01*
X2260105Y1612727D01*
X2260978Y1610684D01*
X2261196Y1607768D01*
X2260978Y1604851D01*
X2260105Y1602809D01*
X2259013Y1601059D01*
X2257703Y1599893D01*
X2255956Y1599018D01*
X2251590D01*
G01X2273893Y1616518D02*
Y1599018D01*
G01X2268871Y1616518D02*
X2278915D01*
G01X2286808Y1599018D02*
Y1616518D01*
G01X2295978D02*
Y1599018D01*
G01Y1607768D02*
X2286808D01*
G01X2307801Y1593185D02*
X2305618Y1596101D01*
X2304526Y1599018D01*
Y1610684D01*
X2305618Y1613601D01*
X2307801Y1616518D01*
G01X2319843Y1599018D02*
Y1610684D01*
G01Y1607476D02*
X2320498Y1608935D01*
X2321590Y1610101D01*
X2323118Y1610684D01*
X2324646Y1610101D01*
X2325738Y1608935D01*
X2326393Y1607476D01*
Y1599018D01*
G01Y1607476D02*
X2327048Y1608935D01*
X2328139Y1610101D01*
X2329668Y1610684D01*
X2331196Y1610101D01*
X2332288Y1608935D01*
X2332943Y1607185D01*
Y1599018D01*
G01X2343893Y1610684D02*
Y1599018D01*
G01Y1615351D02*
X2343456Y1615643D01*
Y1616226D01*
X2343893Y1616518D01*
X2344330Y1616226D01*
Y1615643D01*
X2343893Y1615351D01*
G01X2361393Y1599018D02*
Y1616518D01*
G01X2375618Y1601059D02*
X2376710Y1599893D01*
X2378238Y1599018D01*
X2379548D01*
X2380858Y1599601D01*
X2381731Y1600476D01*
X2382168Y1601642D01*
X2381950Y1603393D01*
X2381076Y1604268D01*
X2377146Y1606018D01*
X2376273Y1608060D01*
X2376710Y1609518D01*
X2377583Y1610393D01*
X2378893Y1610684D01*
X2380203Y1610393D01*
X2381513Y1609518D01*
G01X2397485Y1593185D02*
X2399668Y1596101D01*
X2400760Y1599018D01*
Y1610684D01*
X2399668Y1613601D01*
X2397485Y1616518D01*
G01X2251590Y1566992D02*
X2252899Y1565534D01*
X2254428Y1564660D01*
X2256393Y1564368D01*
X2258358Y1564951D01*
X2259886Y1566118D01*
X2260978Y1568159D01*
X2261196Y1570493D01*
X2260760Y1572826D01*
X2259668Y1574285D01*
X2258139Y1575451D01*
X2256611Y1575743D01*
X2255083Y1575451D01*
X2253118Y1574285D01*
X2253773Y1581868D01*
X2259668D01*
G01X2273893Y1563785D02*
X2273456Y1564076D01*
Y1564660D01*
X2273893Y1564951D01*
X2274330Y1564660D01*
Y1564076D01*
X2273893Y1563785D01*
G01X2291393Y1581868D02*
X2289646Y1581285D01*
X2288336Y1579826D01*
X2287463Y1578077D01*
X2286808Y1575743D01*
X2286590Y1573118D01*
X2286808Y1570493D01*
X2287463Y1568159D01*
X2288336Y1566409D01*
X2289646Y1564951D01*
X2291393Y1564368D01*
X2293139Y1564951D01*
X2294450Y1566409D01*
X2295323Y1568159D01*
X2295978Y1570493D01*
X2296196Y1573118D01*
X2295978Y1575743D01*
X2295323Y1578077D01*
X2294450Y1579826D01*
X2293139Y1581285D01*
X2291393Y1581868D01*
G01X2304963Y1563785D02*
X2312823Y1581868D01*
G01X2322245Y1571659D02*
X2323773Y1573701D01*
X2325083Y1574868D01*
X2326830Y1575451D01*
X2328358Y1574868D01*
X2329450Y1573701D01*
X2330323Y1571951D01*
X2330541Y1569910D01*
X2330323Y1568159D01*
X2329450Y1566409D01*
X2328139Y1564951D01*
X2326611Y1564368D01*
X2324865Y1564951D01*
X2323336Y1566701D01*
X2322463Y1569326D01*
X2322245Y1572243D01*
X2322681Y1576034D01*
X2323336Y1578077D01*
X2324428Y1580118D01*
X2325956Y1581576D01*
X2327485Y1581868D01*
X2329013Y1581285D01*
X2330105Y1579826D01*
G01X2343893Y1563785D02*
X2343456Y1564076D01*
Y1564660D01*
X2343893Y1564951D01*
X2344330Y1564660D01*
Y1564076D01*
X2343893Y1563785D01*
G01X2361393Y1581868D02*
X2359646Y1581285D01*
X2358336Y1579826D01*
X2357463Y1578077D01*
X2356808Y1575743D01*
X2356590Y1573118D01*
X2356808Y1570493D01*
X2357463Y1568159D01*
X2358336Y1566409D01*
X2359646Y1564951D01*
X2361393Y1564368D01*
X2363139Y1564951D01*
X2364450Y1566409D01*
X2365323Y1568159D01*
X2365978Y1570493D01*
X2366196Y1573118D01*
X2365978Y1575743D01*
X2365323Y1578077D01*
X2364450Y1579826D01*
X2363139Y1581285D01*
X2361393Y1581868D01*
G01X2259013Y1529718D02*
Y1547218D01*
X2250934Y1534676D01*
X2261852D01*
G01X2273893Y1529135D02*
X2273456Y1529426D01*
Y1530010D01*
X2273893Y1530301D01*
X2274330Y1530010D01*
Y1529426D01*
X2273893Y1529135D01*
G01X2291393Y1547218D02*
X2289646Y1546635D01*
X2288336Y1545176D01*
X2287463Y1543427D01*
X2286808Y1541093D01*
X2286590Y1538468D01*
X2286808Y1535843D01*
X2287463Y1533509D01*
X2288336Y1531759D01*
X2289646Y1530301D01*
X2291393Y1529718D01*
X2293139Y1530301D01*
X2294450Y1531759D01*
X2295323Y1533509D01*
X2295978Y1535843D01*
X2296196Y1538468D01*
X2295978Y1541093D01*
X2295323Y1543427D01*
X2294450Y1545176D01*
X2293139Y1546635D01*
X2291393Y1547218D01*
G01X2304963Y1529135D02*
X2312823Y1547218D01*
G01X2322681Y1531759D02*
X2324210Y1530301D01*
X2325956Y1529718D01*
X2327703Y1530301D01*
X2329231Y1532051D01*
X2330323Y1534676D01*
X2330760Y1537301D01*
Y1540509D01*
X2330323Y1543134D01*
X2329231Y1545468D01*
X2327921Y1546635D01*
X2326393Y1547218D01*
X2324646Y1546635D01*
X2323336Y1545468D01*
X2322463Y1543718D01*
X2322026Y1541384D01*
X2322463Y1539343D01*
X2323555Y1537301D01*
X2324865Y1536134D01*
X2326393Y1535843D01*
X2328139Y1536426D01*
X2329450Y1537885D01*
X2330760Y1540509D01*
G01X2343893Y1529135D02*
X2343456Y1529426D01*
Y1530010D01*
X2343893Y1530301D01*
X2344330Y1530010D01*
Y1529426D01*
X2343893Y1529135D01*
G01X2361393Y1547218D02*
X2359646Y1546635D01*
X2358336Y1545176D01*
X2357463Y1543427D01*
X2356808Y1541093D01*
X2356590Y1538468D01*
X2356808Y1535843D01*
X2357463Y1533509D01*
X2358336Y1531759D01*
X2359646Y1530301D01*
X2361393Y1529718D01*
X2363139Y1530301D01*
X2364450Y1531759D01*
X2365323Y1533509D01*
X2365978Y1535843D01*
X2366196Y1538468D01*
X2365978Y1541093D01*
X2365323Y1543427D01*
X2364450Y1545176D01*
X2363139Y1546635D01*
X2361393Y1547218D01*
G01X2483893Y1616518D02*
Y1599018D01*
G01X2478871Y1616518D02*
X2488915D01*
G01X2501393Y1599018D02*
Y1606893D01*
X2497026Y1616518D01*
G01X2505760D02*
X2501393Y1606893D01*
G01X2514526Y1599018D02*
Y1616518D01*
X2519766D01*
X2521513Y1615643D01*
X2522823Y1613601D01*
X2523260Y1611268D01*
X2522823Y1608935D01*
X2521731Y1607185D01*
X2519766Y1606309D01*
X2514526D01*
G01X2540760Y1599018D02*
X2532026D01*
Y1616518D01*
X2540760D01*
G01X2537266Y1608060D02*
X2532026D01*
G01X2496590Y1564368D02*
Y1581868D01*
X2500956D01*
X2502703Y1580993D01*
X2504013Y1579826D01*
X2505105Y1578077D01*
X2505978Y1576034D01*
X2506196Y1573118D01*
X2505978Y1570201D01*
X2505105Y1568159D01*
X2504013Y1566409D01*
X2502703Y1565243D01*
X2500956Y1564368D01*
X2496590D01*
G01X2514526D02*
Y1581868D01*
X2519766D01*
X2521513Y1580993D01*
X2522823Y1578951D01*
X2523260Y1576618D01*
X2522823Y1574285D01*
X2521731Y1572535D01*
X2519766Y1571659D01*
X2514526D01*
G01X2496590Y1529718D02*
Y1547218D01*
X2500956D01*
X2502703Y1546343D01*
X2504013Y1545176D01*
X2505105Y1543427D01*
X2505978Y1541384D01*
X2506196Y1538468D01*
X2505978Y1535551D01*
X2505105Y1533509D01*
X2504013Y1531759D01*
X2502703Y1530593D01*
X2500956Y1529718D01*
X2496590D01*
G01X2514526D02*
Y1547218D01*
X2519766D01*
X2521513Y1546343D01*
X2522823Y1544301D01*
X2523260Y1541968D01*
X2522823Y1539635D01*
X2521731Y1537885D01*
X2519766Y1537009D01*
X2514526D01*
G01X2584526Y1599018D02*
Y1616518D01*
X2589985D01*
X2591731Y1615643D01*
X2592823Y1614476D01*
X2593260Y1612143D01*
X2592823Y1609809D01*
X2591513Y1608351D01*
X2589985Y1607476D01*
X2584526D01*
G01X2589985D02*
X2593260Y1599018D01*
G01X2603118Y1606893D02*
X2610105D01*
X2609450Y1608935D01*
X2608358Y1610101D01*
X2606830Y1610684D01*
X2605301Y1610393D01*
X2603991Y1609518D01*
X2603118Y1607476D01*
X2602681Y1605726D01*
Y1603976D01*
X2603118Y1602226D01*
X2604210Y1600476D01*
X2605520Y1599310D01*
X2607048Y1599018D01*
X2608576Y1599601D01*
X2610105Y1601351D01*
G01X2622583Y1599018D02*
Y1613893D01*
X2623020Y1615351D01*
X2623893Y1616226D01*
X2625203Y1616518D01*
X2626513Y1615935D01*
X2627168Y1614476D01*
G01X2624548Y1609518D02*
X2620181D01*
G01X2641393Y1598435D02*
X2640956Y1598726D01*
Y1599310D01*
X2641393Y1599601D01*
X2641830Y1599310D01*
Y1598726D01*
X2641393Y1598435D01*
G01X2672026Y1599018D02*
Y1616518D01*
X2677266D01*
X2679013Y1615643D01*
X2680323Y1613601D01*
X2680760Y1611268D01*
X2680323Y1608935D01*
X2679231Y1607185D01*
X2677266Y1606309D01*
X2672026D01*
G01X2693893Y1599018D02*
Y1616518D01*
G01X2715323Y1599018D02*
Y1610684D01*
G01Y1608643D02*
X2714450Y1609809D01*
X2713139Y1610393D01*
X2711611Y1610684D01*
X2710083Y1610101D01*
X2708773Y1608935D01*
X2707899Y1607185D01*
X2707463Y1604851D01*
X2707899Y1602518D01*
X2708773Y1600768D01*
X2710083Y1599601D01*
X2711611Y1599018D01*
X2713139Y1599310D01*
X2714450Y1600184D01*
X2715323Y1601351D01*
G01X2725181Y1599018D02*
Y1610684D01*
G01Y1607768D02*
X2726055Y1609226D01*
X2727365Y1610393D01*
X2729111Y1610684D01*
X2730639Y1610393D01*
X2731950Y1609226D01*
X2732605Y1607185D01*
Y1599018D01*
G01X2743118Y1606893D02*
X2750105D01*
X2749450Y1608935D01*
X2748358Y1610101D01*
X2746830Y1610684D01*
X2745301Y1610393D01*
X2743991Y1609518D01*
X2743118Y1607476D01*
X2742681Y1605726D01*
Y1603976D01*
X2743118Y1602226D01*
X2744210Y1600476D01*
X2745520Y1599310D01*
X2747048Y1599018D01*
X2748576Y1599601D01*
X2750105Y1601351D01*
G01X2628276Y1581868D02*
Y1564368D01*
X2637010D01*
G01X2649706D02*
X2650143Y1568159D01*
X2650798Y1571368D01*
X2651671Y1574285D01*
X2652763Y1577493D01*
X2654510Y1581868D01*
X2645776D01*
G01X2663713Y1563785D02*
X2671573Y1581868D01*
G01X2680776D02*
Y1564368D01*
X2689510D01*
G01X2698931Y1566409D02*
X2700460Y1564951D01*
X2702206Y1564368D01*
X2703953Y1564951D01*
X2705481Y1566701D01*
X2706573Y1569326D01*
X2707010Y1571951D01*
Y1575159D01*
X2706573Y1577784D01*
X2705481Y1580118D01*
X2704171Y1581285D01*
X2702643Y1581868D01*
X2700896Y1581285D01*
X2699586Y1580118D01*
X2698713Y1578368D01*
X2698276Y1576034D01*
X2698713Y1573993D01*
X2699805Y1571951D01*
X2701115Y1570784D01*
X2702643Y1570493D01*
X2704389Y1571076D01*
X2705700Y1572535D01*
X2707010Y1575159D01*
G01X2628276Y1547218D02*
Y1529718D01*
X2637010D01*
G01X2649706D02*
X2650143Y1533509D01*
X2650798Y1536718D01*
X2651671Y1539635D01*
X2652763Y1542843D01*
X2654510Y1547218D01*
X2645776D01*
G01X2663713Y1529135D02*
X2671573Y1547218D01*
G01X2680776D02*
Y1529718D01*
X2689510D01*
G01X2698931Y1531759D02*
X2700460Y1530301D01*
X2702206Y1529718D01*
X2703953Y1530301D01*
X2705481Y1532051D01*
X2706573Y1534676D01*
X2707010Y1537301D01*
Y1540509D01*
X2706573Y1543134D01*
X2705481Y1545468D01*
X2704171Y1546635D01*
X2702643Y1547218D01*
X2700896Y1546635D01*
X2699586Y1545468D01*
X2698713Y1543718D01*
X2698276Y1541384D01*
X2698713Y1539343D01*
X2699805Y1537301D01*
X2701115Y1536134D01*
X2702643Y1535843D01*
X2704389Y1536426D01*
X2705700Y1537885D01*
X2707010Y1540509D01*
G01X2864193Y1576034D02*
Y1564368D01*
G01Y1580701D02*
X2863756Y1580993D01*
Y1581576D01*
X2864193Y1581868D01*
X2864630Y1581576D01*
Y1580993D01*
X2864193Y1580701D01*
G01X2878418Y1566409D02*
X2879510Y1565243D01*
X2881038Y1564368D01*
X2882348D01*
X2883658Y1564951D01*
X2884531Y1565826D01*
X2884968Y1566992D01*
X2884750Y1568743D01*
X2883876Y1569618D01*
X2879946Y1571368D01*
X2879073Y1573410D01*
X2879510Y1574868D01*
X2880383Y1575743D01*
X2881693Y1576034D01*
X2883003Y1575743D01*
X2884313Y1574868D01*
G01X2911671Y1564368D02*
Y1581868D01*
X2921715Y1564368D01*
Y1581868D01*
G01X2934193Y1564368D02*
X2932446Y1564660D01*
X2930918Y1565826D01*
X2929608Y1567576D01*
X2928734Y1569618D01*
X2928298Y1571951D01*
Y1574285D01*
X2928734Y1576618D01*
X2929608Y1578660D01*
X2930918Y1580409D01*
X2932446Y1581576D01*
X2934193Y1581868D01*
X2935939Y1581576D01*
X2937468Y1580409D01*
X2938778Y1578660D01*
X2939652Y1576618D01*
X2940088Y1574285D01*
Y1571951D01*
X2939652Y1569618D01*
X2938778Y1567576D01*
X2937468Y1565826D01*
X2935939Y1564660D01*
X2934193Y1564368D01*
G01X2951693Y1581868D02*
Y1564368D01*
G01X2946671Y1581868D02*
X2956715D01*
G01X2982981Y1576034D02*
Y1567868D01*
X2983855Y1565826D01*
X2985165Y1564660D01*
X2986693Y1564368D01*
X2988221Y1564660D01*
X2989531Y1565826D01*
X2990405Y1567868D01*
G01Y1564368D02*
Y1576034D01*
G01X3000918Y1566409D02*
X3002010Y1565243D01*
X3003538Y1564368D01*
X3004848D01*
X3006158Y1564951D01*
X3007031Y1565826D01*
X3007468Y1566992D01*
X3007250Y1568743D01*
X3006376Y1569618D01*
X3002446Y1571368D01*
X3001573Y1573410D01*
X3002010Y1574868D01*
X3002883Y1575743D01*
X3004193Y1576034D01*
X3005503Y1575743D01*
X3006813Y1574868D01*
G01X3018418Y1572243D02*
X3025405D01*
X3024750Y1574285D01*
X3023658Y1575451D01*
X3022130Y1576034D01*
X3020601Y1575743D01*
X3019291Y1574868D01*
X3018418Y1572826D01*
X3017981Y1571076D01*
Y1569326D01*
X3018418Y1567576D01*
X3019510Y1565826D01*
X3020820Y1564660D01*
X3022348Y1564368D01*
X3023876Y1564951D01*
X3025405Y1566701D01*
G01X3043123Y1581868D02*
Y1564368D01*
G01Y1566992D02*
X3042250Y1565534D01*
X3040939Y1564660D01*
X3039411Y1564368D01*
X3037665Y1564951D01*
X3036355Y1566409D01*
X3035481Y1568159D01*
X3035263Y1570201D01*
X3035481Y1572243D01*
X3036355Y1573993D01*
X3037665Y1575451D01*
X3039411Y1576034D01*
X3040939Y1575743D01*
X3042031Y1575159D01*
X3043123Y1573993D01*
G01X2789390Y1598435D02*
X2798996Y1611268D01*
G01X2794193Y1613601D02*
Y1596101D01*
G01X2798996Y1598435D02*
X2789390Y1611268D01*
G01X2787643Y1604851D02*
X2800743D01*
G01X2826355D02*
X2832031D01*
G01X2859390Y1599018D02*
Y1616518D01*
X2863756D01*
X2865503Y1615643D01*
X2866813Y1614476D01*
X2867905Y1612727D01*
X2868778Y1610684D01*
X2868996Y1607768D01*
X2868778Y1604851D01*
X2867905Y1602809D01*
X2866813Y1601059D01*
X2865503Y1599893D01*
X2863756Y1599018D01*
X2859390D01*
G01X2878418Y1606893D02*
X2885405D01*
X2884750Y1608935D01*
X2883658Y1610101D01*
X2882130Y1610684D01*
X2880601Y1610393D01*
X2879291Y1609518D01*
X2878418Y1607476D01*
X2877981Y1605726D01*
Y1603976D01*
X2878418Y1602226D01*
X2879510Y1600476D01*
X2880820Y1599310D01*
X2882348Y1599018D01*
X2883876Y1599601D01*
X2885405Y1601351D01*
G01X2895481Y1599018D02*
Y1610684D01*
G01Y1607768D02*
X2896355Y1609226D01*
X2897665Y1610393D01*
X2899411Y1610684D01*
X2900939Y1610393D01*
X2902250Y1609226D01*
X2902905Y1607185D01*
Y1599018D01*
G01X2916693D02*
X2915383Y1599310D01*
X2914073Y1600476D01*
X2913199Y1602518D01*
X2912763Y1604851D01*
X2913199Y1607185D01*
X2914073Y1609226D01*
X2915383Y1610393D01*
X2916693Y1610684D01*
X2918003Y1610393D01*
X2919313Y1609226D01*
X2920186Y1607185D01*
X2920405Y1604851D01*
X2920186Y1602518D01*
X2919313Y1600476D01*
X2918003Y1599310D01*
X2916693Y1599018D01*
G01X2934193Y1616518D02*
Y1599018D01*
G01X2931136Y1610684D02*
X2937250D01*
G01X2948418Y1606893D02*
X2955405D01*
X2954750Y1608935D01*
X2953658Y1610101D01*
X2952130Y1610684D01*
X2950601Y1610393D01*
X2949291Y1609518D01*
X2948418Y1607476D01*
X2947981Y1605726D01*
Y1603976D01*
X2948418Y1602226D01*
X2949510Y1600476D01*
X2950820Y1599310D01*
X2952348Y1599018D01*
X2953876Y1599601D01*
X2955405Y1601351D01*
G01X2965918Y1601059D02*
X2967010Y1599893D01*
X2968538Y1599018D01*
X2969848D01*
X2971158Y1599601D01*
X2972031Y1600476D01*
X2972468Y1601642D01*
X2972250Y1603393D01*
X2971376Y1604268D01*
X2967446Y1606018D01*
X2966573Y1608060D01*
X2967010Y1609518D01*
X2967883Y1610393D01*
X2969193Y1610684D01*
X2970503Y1610393D01*
X2971813Y1609518D01*
G01X3004193Y1616518D02*
Y1599018D01*
G01X3001136Y1610684D02*
X3007250D01*
G01X3017981Y1599018D02*
Y1616518D01*
G01Y1608060D02*
X3019073Y1609518D01*
X3020165Y1610393D01*
X3021911Y1610684D01*
X3023221Y1610393D01*
X3024750Y1609226D01*
X3025405Y1607476D01*
Y1599018D01*
G01X3043123D02*
Y1610684D01*
G01Y1608643D02*
X3042250Y1609809D01*
X3040939Y1610393D01*
X3039411Y1610684D01*
X3037883Y1610101D01*
X3036573Y1608935D01*
X3035699Y1607185D01*
X3035263Y1604851D01*
X3035699Y1602518D01*
X3036573Y1600768D01*
X3037883Y1599601D01*
X3039411Y1599018D01*
X3040939Y1599310D01*
X3042250Y1600184D01*
X3043123Y1601351D01*
G01X3056693Y1616518D02*
Y1599018D01*
G01X3053636Y1610684D02*
X3059750D01*
G01X3091693Y1616518D02*
Y1599018D01*
G01X3088636Y1610684D02*
X3094750D01*
G01X3105481Y1599018D02*
Y1616518D01*
G01Y1608060D02*
X3106573Y1609518D01*
X3107665Y1610393D01*
X3109411Y1610684D01*
X3110721Y1610393D01*
X3112250Y1609226D01*
X3112905Y1607476D01*
Y1599018D01*
G01X3126693Y1610684D02*
Y1599018D01*
G01Y1615351D02*
X3126256Y1615643D01*
Y1616226D01*
X3126693Y1616518D01*
X3127130Y1616226D01*
Y1615643D01*
X3126693Y1615351D01*
G01X3140918Y1601059D02*
X3142010Y1599893D01*
X3143538Y1599018D01*
X3144848D01*
X3146158Y1599601D01*
X3147031Y1600476D01*
X3147468Y1601642D01*
X3147250Y1603393D01*
X3146376Y1604268D01*
X3142446Y1606018D01*
X3141573Y1608060D01*
X3142010Y1609518D01*
X3142883Y1610393D01*
X3144193Y1610684D01*
X3145503Y1610393D01*
X3146813Y1609518D01*
G01X3176573Y1616518D02*
X3181813D01*
G01X3179193D02*
Y1599018D01*
G01X3176573D02*
X3181813D01*
G01X3190143D02*
Y1610684D01*
G01Y1607476D02*
X3190798Y1608935D01*
X3191890Y1610101D01*
X3193418Y1610684D01*
X3194946Y1610101D01*
X3196038Y1608935D01*
X3196693Y1607476D01*
Y1599018D01*
G01Y1607476D02*
X3197348Y1608935D01*
X3198439Y1610101D01*
X3199968Y1610684D01*
X3201496Y1610101D01*
X3202588Y1608935D01*
X3203243Y1607185D01*
Y1599018D01*
G01X3210263Y1593185D02*
Y1610684D01*
G01Y1608060D02*
X3211355Y1609518D01*
X3212446Y1610393D01*
X3214193Y1610684D01*
X3215721Y1610393D01*
X3217250Y1608935D01*
X3217905Y1606893D01*
X3218123Y1604851D01*
X3217905Y1602809D01*
X3217250Y1600768D01*
X3215939Y1599601D01*
X3214193Y1599018D01*
X3212665Y1599310D01*
X3211136Y1600184D01*
X3210263Y1601351D01*
G01X3228418Y1606893D02*
X3235405D01*
X3234750Y1608935D01*
X3233658Y1610101D01*
X3232130Y1610684D01*
X3230601Y1610393D01*
X3229291Y1609518D01*
X3228418Y1607476D01*
X3227981Y1605726D01*
Y1603976D01*
X3228418Y1602226D01*
X3229510Y1600476D01*
X3230820Y1599310D01*
X3232348Y1599018D01*
X3233876Y1599601D01*
X3235405Y1601351D01*
G01X3253123Y1616518D02*
Y1599018D01*
G01Y1601642D02*
X3252250Y1600184D01*
X3250939Y1599310D01*
X3249411Y1599018D01*
X3247665Y1599601D01*
X3246355Y1601059D01*
X3245481Y1602809D01*
X3245263Y1604851D01*
X3245481Y1606893D01*
X3246355Y1608643D01*
X3247665Y1610101D01*
X3249411Y1610684D01*
X3250939Y1610393D01*
X3252031Y1609809D01*
X3253123Y1608643D01*
G01X3270623Y1599018D02*
Y1610684D01*
G01Y1608643D02*
X3269750Y1609809D01*
X3268439Y1610393D01*
X3266911Y1610684D01*
X3265383Y1610101D01*
X3264073Y1608935D01*
X3263199Y1607185D01*
X3262763Y1604851D01*
X3263199Y1602518D01*
X3264073Y1600768D01*
X3265383Y1599601D01*
X3266911Y1599018D01*
X3268439Y1599310D01*
X3269750Y1600184D01*
X3270623Y1601351D01*
G01X3280481Y1599018D02*
Y1610684D01*
G01Y1607768D02*
X3281355Y1609226D01*
X3282665Y1610393D01*
X3284411Y1610684D01*
X3285939Y1610393D01*
X3287250Y1609226D01*
X3287905Y1607185D01*
Y1599018D01*
G01X3305186Y1609226D02*
X3303658Y1610393D01*
X3302348Y1610684D01*
X3300601Y1610101D01*
X3299291Y1608935D01*
X3298418Y1606893D01*
X3298199Y1604851D01*
X3298418Y1602809D01*
X3299291Y1601059D01*
X3300601Y1599601D01*
X3302348Y1599018D01*
X3303876Y1599601D01*
X3305186Y1600768D01*
G01X3315918Y1606893D02*
X3322905D01*
X3322250Y1608935D01*
X3321158Y1610101D01*
X3319630Y1610684D01*
X3318101Y1610393D01*
X3316791Y1609518D01*
X3315918Y1607476D01*
X3315481Y1605726D01*
Y1603976D01*
X3315918Y1602226D01*
X3317010Y1600476D01*
X3318320Y1599310D01*
X3319848Y1599018D01*
X3321376Y1599601D01*
X3322905Y1601351D01*
G01X0Y-137756D02*
G03X15000Y-152756I15000J0D01*
G01X0Y-137756D02*
G03X15000Y-152756I15000J0D01*
G01X0Y-11811D02*
Y-137756D01*
G01Y-11811D02*
Y-137756D01*
G01X854331Y-152756D02*
X15000D01*
G01X854331D02*
X15000D01*
G01X23622Y-7874D02*
G03Y0I0J3937D01*
G01Y-7874D02*
G03Y0I0J3937D01*
G01X0Y3937D02*
G03X3937Y0I3937J0D01*
G01Y-7874D02*
X23622D01*
G01X0Y3937D02*
G03X3937Y0I3937J0D01*
G01Y-7874D02*
X23622D01*
G01X3937D02*
G03X0Y-11811I0J-3937D01*
G01X3937Y-7874D02*
G03X0Y-11811I0J-3937D01*
G01X3937Y0D02*
X397638D01*
G01X3937D02*
X397638D01*
G01X0Y1370866D02*
Y3937D01*
G01Y1370866D02*
Y3937D01*
G01X3937Y1374803D02*
G03X0Y1370866I0J-3937D01*
G01X3937Y1374803D02*
G03X0Y1370866I0J-3937D01*
G01X23622Y1374803D02*
G03Y1382677I0J3937D01*
G01Y1374803D02*
G03Y1382677I0J3937D01*
G01X3937D02*
X23622D01*
G01X0Y1386614D02*
G03X3937Y1382677I3937J0D01*
G01D02*
X23622D01*
G01X0Y1386614D02*
G03X3937Y1382677I3937J0D01*
G01Y1374803D02*
X746850D01*
G01D02*
X3937D01*
G01X0Y1386614D02*
Y1643268D01*
G01Y1386614D02*
Y1643268D01*
G01X15000Y1658268D02*
G03X0Y1643268I0J-15000D01*
G01X15000Y1658268D02*
G03X0Y1643268I0J-15000D01*
G01X775591Y1658268D02*
X15000D01*
G01X775591D02*
X15000D01*
G01X54331Y-7874D02*
X323228D01*
G01X54331D02*
X323228D01*
G01X54331Y0D02*
G03Y-7874I0J-3937D01*
G01Y0D02*
G03Y-7874I0J-3937D01*
G01Y1382677D02*
G03Y1374803I0J-3937D01*
G01Y1382677D02*
G03Y1374803I0J-3937D01*
G01Y1382677D02*
X353740D01*
G01X54331D02*
X353740D01*
G01X114295Y378885D02*
G03X148106I16905J-13531D01*
G01X114295D02*
G03X148106I16905J-13531D01*
G01X114295D02*
G03X121220Y392016I-30737J24602D01*
G01X114295Y378885D02*
G03X121220Y392016I-30737J24602D01*
G01X114295Y831641D02*
G03X121220Y844772I-30737J24601D01*
G01X114295Y831641D02*
G03X121220Y844772I-30737J24602D01*
G01X114295Y831641D02*
G03X148106I16905J-13531D01*
G01X114295D02*
G03X148106I16905J-13531D01*
G01X114295Y1284397D02*
G03X148106I16905J-13531D01*
G01X114295D02*
G03X148106I16905J-13531D01*
G01X114295D02*
G03X121220Y1297528I-30737J24601D01*
G01X114295Y1284397D02*
G03X121220Y1297528I-30737J24602D01*
G01X141181Y392016D02*
G03X121220I-9980J-3039D01*
G01X141181D02*
G03X148106Y378885I37662J11471D01*
G01X141181Y392016D02*
G03X121220I-9980J-3039D01*
G01X141181D02*
G03X148106Y378885I37662J11471D01*
G01X141181Y844772D02*
G03X148106Y831641I37662J11471D01*
G01X141181Y844772D02*
G03X148106Y831641I37662J11471D01*
G01X141181Y844772D02*
G03X121220I-9980J-3040D01*
G01X141181D02*
G03X121220I-9980J-3039D01*
G01X141181Y1297528D02*
G03X121220I-9980J-3040D01*
G01X141181D02*
G03X148106Y1284397I37662J11471D01*
G01X141181Y1297528D02*
G03X121220I-9980J-3040D01*
G01X141181D02*
G03X148106Y1284397I37662J11471D01*
G01X323228Y-7874D02*
G03Y0I0J3937D01*
G01Y-7874D02*
G03Y0I0J3937D01*
G01X362598D02*
G03Y-7874I0J-3937D01*
G01Y0D02*
G03Y-7874I0J-3937D01*
G01X362327Y378885D02*
G03X396138I16905J-13531D01*
G01X362327D02*
G03X396138I16905J-13531D01*
G01X362327D02*
G03X369252Y392016I-30737J24602D01*
G01X362327Y378885D02*
G03X369252Y392016I-30737J24602D01*
G01X362327Y831641D02*
G03X369252Y844772I-30737J24602D01*
G01X362327Y831641D02*
G03X369252Y844772I-30737J24602D01*
G01X362327Y831641D02*
G03X396138I16905J-13531D01*
G01X362327D02*
G03X396138I16905J-13531D01*
G01X362327Y1284397D02*
G03X396138I16905J-13531D01*
G01X362327D02*
G03X396138I16905J-13531D01*
G01X362327D02*
G03X369252Y1297528I-30737J24602D01*
G01X362327Y1284397D02*
G03X369252Y1297528I-30737J24602D01*
G01X353740Y1374803D02*
G03Y1382677I0J3937D01*
G01Y1374803D02*
G03Y1382677I0J3937D01*
G01X401575Y3937D02*
Y55118D01*
G01X397638Y0D02*
G03X401575Y3937I0J3937D01*
G01X409449D02*
Y51181D01*
G01X397638Y-7874D02*
G03X409449Y3937I0J11811D01*
G01X397638Y0D02*
G03X401575Y3937I0J3937D01*
G01D02*
Y55118D01*
G01X409449Y3937D02*
Y51181D01*
G01X397638Y-7874D02*
G03X409449Y3937I0J11811D01*
G01X362598Y-7874D02*
X397638D01*
G01X362598D02*
X397638D01*
G01X405512Y59055D02*
G03X401575Y55118I0J-3937D01*
G01X405512Y59055D02*
G03X401575Y55118I0J-3937D01*
G01X405512Y59055D02*
X586614D01*
G01X409449Y51181D02*
X582677D01*
G01X405512Y59055D02*
X586614D01*
G01X409449Y51181D02*
X582677D01*
G01X389213Y392016D02*
G03X396138Y378885I37662J11471D01*
G01X389213Y392016D02*
G03X396138Y378885I37662J11471D01*
G01X389213Y392016D02*
G03X369252I-9981J-3039D01*
G01X389213D02*
G03X369252I-9981J-3039D01*
G01X389213Y844772D02*
G03X396138Y831641I37662J11471D01*
G01X389213Y844772D02*
G03X396138Y831641I37662J11471D01*
G01X389213Y844772D02*
G03X369252I-9981J-3040D01*
G01X389213D02*
G03X369252I-9981J-3039D01*
G01X389213Y1297528D02*
G03X396138Y1284397I37662J11471D01*
G01X389213Y1297528D02*
G03X396138Y1284397I37662J11471D01*
G01X389213Y1297528D02*
G03X369252I-9981J-3040D01*
G01X389213D02*
G03X369252I-9981J-3040D01*
G01X393110Y1382677D02*
G03Y1374803I0J-3937D01*
G01Y1382677D02*
X692520D01*
G01X393110D02*
X692520D01*
G01X393110D02*
G03Y1374803I0J-3937D01*
G01X523327Y829921D02*
G03X483169I-20079J0D01*
G01X523327D02*
G03I-20079J0D01*
G01X483169D02*
G03X523327I20079J0D01*
G01X594488Y-7874D02*
X628765D01*
G01X594488D02*
X628765D01*
G01X590551Y55118D02*
Y3937D01*
G01D02*
G03X594488Y0I3937J0D01*
G01X582677Y51181D02*
Y3937D01*
G01D02*
G03X594488Y-7874I11811J0D01*
G01X590551Y55118D02*
Y3937D01*
G01D02*
G03X594488Y0I3937J0D01*
G01X582677Y51181D02*
Y3937D01*
G01D02*
G03X594488Y-7874I11811J0D01*
G01Y0D02*
X783465D01*
G01X594488D02*
X783465D01*
G01X590551Y55118D02*
G03X586614Y59055I-3937J0D01*
G01X590551Y55118D02*
G03X586614Y59055I-3937J0D01*
G01X628765Y-7874D02*
G03Y0I0J3937D01*
G01Y-7874D02*
G03Y0I0J3937D01*
G01X610358Y378885D02*
G03X644169I16906J-13531D01*
G01X610358D02*
G03X644169I16906J-13531D01*
G01X637244Y392016D02*
G03X644169Y378885I37662J11471D01*
G01X637244Y392016D02*
G03X644169Y378885I37662J11471D01*
G01X637244Y392016D02*
G03X617283I-9980J-3039D01*
G01X637244D02*
G03X617283I-9980J-3039D01*
G01X610358Y378885D02*
G03X617283Y392016I-30737J24602D01*
G01X610358Y378885D02*
G03X617283Y392016I-30737J24602D01*
G01X637244Y844772D02*
G03X644169Y831641I37662J11471D01*
G01X637244Y844772D02*
G03X644169Y831641I37662J11471D01*
G01X610358D02*
G03X617283Y844772I-30737J24601D01*
G01X610358Y831641D02*
G03X617283Y844772I-30737J24602D01*
G01X610358Y831641D02*
G03X644169I16906J-13531D01*
G01X610358D02*
G03X644169I16906J-13531D01*
G01X637244Y844772D02*
G03X617283I-9980J-3040D01*
G01X637244D02*
G03X617283I-9980J-3039D01*
G01X610358Y1284397D02*
G03X644169I16906J-13531D01*
G01X610358D02*
G03X644169I16906J-13531D01*
G01X637244Y1297528D02*
G03X644169Y1284397I37662J11471D01*
G01X637244Y1297528D02*
G03X644169Y1284397I37662J11471D01*
G01X610358D02*
G03X617283Y1297528I-30737J24601D01*
G01X637244D02*
G03X617283I-9980J-3040D01*
G01X610358Y1284397D02*
G03X617283Y1297528I-30737J24602D01*
G01X637244D02*
G03X617283I-9980J-3040D01*
G01X659474Y0D02*
G03Y-7874I0J-3937D01*
G01Y0D02*
G03Y-7874I0J-3937D01*
G01D02*
X780203D01*
G01X659474D02*
X780203D01*
G01X692520Y1374803D02*
G03Y1382677I0J3937D01*
G01Y1374803D02*
G03Y1382677I0J3937D01*
G01X746850Y1374803D02*
G03X750787Y1378740I0J3937D01*
G01X746850Y1374803D02*
G03X750787Y1378740I0J3937D01*
G01X723228Y1382677D02*
G03Y1374803I0J-3937D01*
G01Y1382677D02*
X742913D01*
G01X723228D02*
X742913D01*
G01X723228D02*
G03Y1374803I0J-3937D01*
G01X742913Y1464567D02*
Y1382677D01*
G01Y1464567D02*
Y1382677D01*
G01X754724Y1476378D02*
G03X742913Y1464567I0J-11811D01*
G01X754724Y1476378D02*
G03X742913Y1464567I0J-11811D01*
G01X862205Y-7874D02*
X791339D01*
G01X787402Y-3937D02*
G03X791339Y-7874I3937J0D01*
G01X787402Y-3937D02*
G03X791339Y-7874I3937J0D01*
G01D02*
X862205D01*
G01X858268Y-15748D02*
X791339D01*
G01X858268D02*
X791339D01*
G01X787402Y-3937D02*
G03X783465Y0I-3937J0D01*
G01X787402Y-3937D02*
G03X783465Y0I-3937J0D01*
G01X780203Y-7874D02*
G03X791339Y-15748I11136J3937D01*
G01X780203Y-7874D02*
G03X791339Y-15748I11136J3937D01*
G01X779551Y264712D02*
G03X813362I16905J-13531D01*
G01X779551D02*
G03X813362I16905J-13531D01*
G01X779551D02*
G03X786476Y277843I-30737J24601D01*
G01X806437D02*
G03X786476I-9981J-3040D01*
G01X779551Y264712D02*
G03X786476Y277843I-30737J24602D01*
G01X806437D02*
G03X786476I-9981J-3040D01*
G01X779551Y737153D02*
G03X786476Y750284I-30737J24601D01*
G01X779551Y737154D02*
G03X786476Y750284I-30736J24602D01*
G01X779551Y737153D02*
G03X813362I16905J-13531D01*
G01X779551D02*
G03X813362I16905J-13531D01*
G01X806437Y750284D02*
G03X786476I-9981J-3040D01*
G01X806437D02*
G03X786476I-9981J-3040D01*
G01X750787Y1464567D02*
Y1378740D01*
G01Y1464567D02*
Y1378740D01*
G01X783465Y1468504D02*
G03X787402Y1472441I0J3937D01*
G01X783465Y1468504D02*
G03X787402Y1472441I0J3937D01*
G01X783465Y1468504D02*
X754724D01*
G01D02*
G03X750787Y1464567I0J-3937D01*
G01X783465Y1468504D02*
X754724D01*
G01D02*
G03X750787Y1464567I0J-3937D01*
G01X779528Y1476378D02*
X754724D01*
G01X779528D02*
X754724D01*
G01X787402Y1654331D02*
Y1472441D01*
G01X779528Y1596063D02*
Y1476378D01*
G01X787402Y1654331D02*
Y1472441D01*
G01X779528Y1596063D02*
Y1476378D01*
G01X787402Y1596063D02*
G03X779528I-3937J0D01*
G01X787402D02*
G03X779528I-3937J0D01*
G01X1216535Y1658268D02*
X791339D01*
G01D02*
G03X787402Y1654331I0J-3937D01*
G01X779528D02*
G03X775591Y1658268I-3937J0D01*
G01X1216535D02*
X791339D01*
G01D02*
G03X787402Y1654331I0J-3937D01*
G01X779528D02*
G03X775591Y1658268I-3937J0D01*
G01X779528Y1654331D02*
Y1626772D01*
G01D02*
G03X787402I3937J0D01*
G01X779528Y1654331D02*
Y1626772D01*
G01D02*
G03X787402I3937J0D01*
G01X806437Y277843D02*
G03X813362Y264712I37662J11471D01*
G01X806437Y277843D02*
G03X813362Y264712I37662J11471D01*
G01X806437Y750284D02*
G03X813362Y737153I37662J11471D01*
G01X806437Y750284D02*
G03X813362Y737154I37661J11472D01*
G01X866142Y-148819D02*
Y-11811D01*
G01Y-148819D02*
G03X870079Y-152756I3937J0D01*
G01X866142Y-11811D02*
Y-148819D01*
G01D02*
G03X870079Y-152756I3937J0D01*
G01X866142Y-129134D02*
G03X858268I-3937J0D01*
G01X866142D02*
G03X858268I-3937J0D01*
G01Y-148819D02*
Y-129134D01*
G01X854331Y-152756D02*
G03X858268Y-148819I0J3937D01*
G01D02*
Y-129134D01*
G01X854331Y-152756D02*
G03X858268Y-148819I0J3937D01*
G01X1177165Y-152756D02*
X870079D01*
G01D02*
X1177165D01*
G01X858268Y-98425D02*
Y-15748D01*
G01Y-98425D02*
Y-15748D01*
G01Y-98425D02*
G03X866142I3937J0D01*
G01X858268D02*
G03X866142I3937J0D01*
G01Y-11811D02*
G03X862205Y-7874I-3937J0D01*
G01X866142Y-11811D02*
G03X862205Y-7874I-3937J0D01*
G01X927032Y-57820D02*
G03X962731I17850J-12259D01*
G01X927032Y-57821D02*
G03X962732I17850J-12258D01*
G01X927032Y-57820D02*
G03X935199Y-42571I-64908J44575D01*
G01X954565D02*
G03X935199I-9683J-3885D01*
G01X927032Y-57821D02*
G03X935199Y-42571I-64909J44573D01*
G01X954564D02*
G03X935199I-9682J-3885D01*
G01X944512Y1089122D02*
G03X978323I16905J-13531D01*
G01X944512Y1089121D02*
G03X978323I16905J-13531D01*
G01X944512Y1431641D02*
G03X978323I16905J-13531D01*
G01X944512D02*
G03X978323I16905J-13531D01*
G01X954565Y-42571D02*
G03X962731Y-57820I73077J29322D01*
G01X954564Y-42570D02*
G03X962732Y-57821I73076J29324D01*
G01X971398Y1102252D02*
G03X978323Y1089122I37661J11472D01*
G01X971398Y1102252D02*
G03X978323Y1089121I37662J11471D01*
G01X971398Y1102252D02*
G03X951437I-9980J-3039D01*
G01X971398D02*
G03X951437I-9980J-3039D01*
G01X944512Y1089122D02*
G03X951437Y1102252I-30737J24602D01*
G01X944512Y1089121D02*
G03X951437Y1102252I-30737J24602D01*
G01X971398Y1444772D02*
G03X978323Y1431641I37662J11471D01*
G01X971398Y1444772D02*
G03X978323Y1431641I37662J11471D01*
G01X971398Y1444772D02*
G03X951437I-9980J-3040D01*
G01X944512Y1431641D02*
G03X951437Y1444772I-30737J24602D01*
G01X944512Y1431641D02*
G03X951437Y1444772I-30737J24602D01*
G01X971398D02*
G03X951437I-9980J-3039D01*
G01X1181102Y-148819D02*
Y-3937D01*
G01X1177165Y-152756D02*
G03X1181102Y-148819I0J3937D01*
G01X1177165Y-152756D02*
G03X1181102Y-148819I0J3937D01*
G01D02*
Y-3937D01*
G01Y-94488D02*
G03X1188976I3937J0D01*
G01X1181102D02*
G03X1188976I3937J0D01*
G01Y-125197D02*
G03X1181102I-3937J0D01*
G01X1188976D02*
G03X1181102I-3937J0D01*
G01X1185039Y0D02*
G03X1181102Y-3937I0J-3937D01*
G01X1185039Y0D02*
G03X1181102Y-3937I0J-3937D01*
G01X1164984Y557626D02*
G03X1198795I16906J-13531D01*
G01X1164984Y557625D02*
G03X1198795I16906J-13531D01*
G01X1191870Y570756D02*
G03X1171909I-9980J-3039D01*
G01X1191870D02*
G03X1171909I-9980J-3039D01*
G01X1164984Y557626D02*
G03X1171909Y570756I-30736J24602D01*
G01X1164984Y557625D02*
G03X1171909Y570756I-30737J24602D01*
G01X1164984Y971011D02*
G03X1198795I16906J-13531D01*
G01X1164984D02*
G03X1198795I16906J-13531D01*
G01X1191870Y984142D02*
G03X1171909I-9980J-3040D01*
G01X1191870D02*
G03X1171909I-9980J-3039D01*
G01X1164984Y971011D02*
G03X1171909Y984142I-30737J24602D01*
G01X1164984Y971011D02*
G03X1171909Y984142I-30737J24602D01*
G01X1164173Y1378740D02*
Y1468504D01*
G01X1930906Y1374803D02*
X1168110D01*
G01X1164173Y1378740D02*
G03X1168110Y1374803I3937J0D01*
G01X1172047Y1382677D02*
Y1464567D01*
G01X1195669Y1382677D02*
X1172047D01*
G01X1930906Y1374803D02*
X1168110D01*
G01X1164173Y1378740D02*
G03X1168110Y1374804I3937J1D01*
G01X1164173Y1378740D02*
Y1468504D01*
G01X1172047Y1382677D02*
Y1464567D01*
G01X1195669Y1382677D02*
X1172047D01*
G01X1168110Y1472441D02*
G03X1164173Y1468504I0J-3937D01*
G01X1168110Y1472441D02*
G03X1164173Y1468504I0J-3937D01*
G01X1172047Y1464567D02*
X1216535D01*
G01X1172047D02*
X1216535D01*
G01X1168110Y1472441D02*
X1216535D01*
G01X1168110D02*
X1216535D01*
G01X1164984Y1561563D02*
G03X1171909Y1574693I-30736J24602D01*
G01X1164984Y1561562D02*
G03X1171909Y1574693I-30737J24602D01*
G01X1164984Y1561563D02*
G03X1198795I16906J-13531D01*
G01X1164984Y1561562D02*
G03X1198795I16906J-13531D01*
G01X1191870Y1574693D02*
G03X1171909I-9980J-3039D01*
G01X1191870D02*
G03X1171909I-9980J-3039D01*
G01X1188976Y-148819D02*
Y-125197D01*
G01Y-148819D02*
G03X1192913Y-152756I3937J0D01*
G01X1188976Y-148819D02*
Y-125197D01*
G01Y-148819D02*
G03X1192913Y-152756I3937J0D01*
G01D02*
X1919843D01*
G01X1192913D02*
X1919843D01*
G01X1188976Y-94488D02*
Y-7874D01*
G01Y-94488D02*
Y-7874D01*
G01X1185039Y0D02*
X1366142D01*
G01X1188976Y-7874D02*
X1315748D01*
G01X1185039Y0D02*
X1366142D01*
G01X1188976Y-7874D02*
X1315748D01*
G01X1191870Y570756D02*
G03X1198795Y557626I37662J11472D01*
G01X1191870Y570756D02*
G03X1198795Y557626I37662J11472D01*
G01X1191870Y984142D02*
G03X1198795Y971011I37662J11471D01*
G01X1191870Y984142D02*
G03X1198795Y971011I37662J11471D01*
G01X1524606Y1382677D02*
X1226378D01*
G01X1524606D02*
X1226378D01*
G01X1195669Y1374803D02*
G03Y1382677I0J3937D01*
G01X1226378D02*
G03Y1374803I0J-3937D01*
G01X1195669D02*
G03Y1382677I0J3937D01*
G01X1226378D02*
G03Y1374803I0J-3937D01*
G01X1216535Y1464567D02*
G03X1228346Y1476378I0J11811D01*
G01X1216535Y1464567D02*
G03X1228346Y1476378I0J11811D01*
G01Y1592126D02*
Y1476378D01*
G01Y1592126D02*
Y1476378D01*
G01X1220472Y1654331D02*
Y1476378D01*
G01X1216535Y1472441D02*
G03X1220472Y1476378I0J3937D01*
G01X1216535Y1472441D02*
G03X1220472Y1476378I0J3937D01*
G01D02*
Y1654331D01*
G01X1191870Y1574693D02*
G03X1198795Y1561563I37662J11472D01*
G01X1191870Y1574693D02*
G03X1198795Y1561562I37662J11471D01*
G01X1228346Y1592126D02*
G03X1220472I-3937J0D01*
G01X1228346D02*
G03X1220472I-3937J0D01*
G01X1232283Y1658268D02*
X1442382D01*
G01X1232283D02*
G03X1228346Y1654331I0J-3937D01*
G01X1232283Y1658268D02*
X1442382D01*
G01X1232283D02*
G03X1228346Y1654331I0J-3937D01*
G01D02*
Y1622835D01*
G01Y1654331D02*
Y1622835D01*
G01X1220472Y1654331D02*
G03X1216535Y1658268I-3937J0D01*
G01X1220472Y1654331D02*
G03X1216535Y1658268I-3937J0D01*
G01X1220472Y1622835D02*
G03X1228346I3937J0D01*
G01X1220472D02*
G03X1228346I3937J0D01*
G01X1284965Y378885D02*
G03X1318776I16906J-13531D01*
G01X1284965D02*
G03X1318775I16905J-13531D01*
G01X1284965Y831641D02*
G03X1318776I16906J-13531D01*
G01X1284965D02*
G03X1318775I16905J-13531D01*
G01X1284965Y1284397D02*
G03X1318776I16906J-13531D01*
G01X1284965D02*
G03X1318775I16905J-13531D01*
G01X1315748Y-7874D02*
G03Y0I0J3937D01*
G01Y-7874D02*
G03Y0I0J3937D01*
G01X1311850Y392016D02*
G03X1291890I-9980J-3040D01*
G01X1311850D02*
G03X1318776Y378885I37662J11473D01*
G01X1311851Y392016D02*
G03X1291890I-9980J-3039D01*
G01X1311851D02*
G03X1318775Y378885I37663J11469D01*
G01X1284965D02*
G03X1291890Y392016I-30737J24602D01*
G01X1284965Y378885D02*
G03X1291890Y392016I-30737J24602D01*
G01X1284965Y831641D02*
G03X1291890Y844772I-30737J24602D01*
G01X1311850D02*
G03X1318776Y831641I37662J11473D01*
G01X1284965D02*
G03X1291890Y844772I-30737J24602D01*
G01X1311851D02*
G03X1318775Y831641I37663J11469D01*
G01X1311850Y844772D02*
G03X1291890I-9980J-3040D01*
G01X1311851D02*
G03X1291890I-9980J-3039D01*
G01X1284965Y1284397D02*
G03X1291890Y1297528I-30737J24602D01*
G01X1311850D02*
G03X1291890I-9980J-3040D01*
G01X1311850D02*
G03X1318776Y1284397I37661J11473D01*
G01X1284965D02*
G03X1291890Y1297528I-30737J24602D01*
G01X1311851D02*
G03X1291890I-9980J-3040D01*
G01X1311851D02*
G03X1318775Y1284397I37663J11469D01*
G01X1377953Y3937D02*
Y51181D01*
G01Y3937D02*
Y51181D01*
G01X1370079Y3937D02*
Y55118D01*
G01X1366142Y0D02*
G03X1370079Y3937I0J3937D01*
G01X1366142Y-7874D02*
G03X1377953Y3937I0J11811D01*
G01X1346457Y-7874D02*
X1366142D01*
G01Y0D02*
G03X1370079Y3937I0J3937D01*
G01D02*
Y55118D01*
G01X1346457Y-7874D02*
X1366142D01*
G01D02*
G03X1377953Y3937I0J11811D01*
G01X1346457Y0D02*
G03Y-7874I0J-3937D01*
G01Y0D02*
G03Y-7874I0J-3937D01*
G01X1374016Y59055D02*
G03X1370079Y55118I0J-3937D01*
G01X1374016Y59056D02*
G03X1370079Y55118I0J-3937D01*
G01X1374016Y59055D02*
X1555118D01*
G01X1377953Y51181D02*
X1551181D01*
G01X1374016Y59055D02*
X1555118D01*
G01X1377953Y51181D02*
X1551181D01*
G01X1442382Y1658268D02*
G03X1450256I3937J0D01*
G01X1442382D02*
G03X1450256I3937J0D01*
G01D02*
X1919843D01*
G01X1450256D02*
X1919843D01*
G01X1562992Y0D02*
X1930906D01*
G01X1559055Y55118D02*
Y3937D01*
G01D02*
G03X1562992Y0I3937J0D01*
G01Y-7874D02*
X1593701D01*
G01X1559055Y55118D02*
Y3937D01*
G01D02*
G03X1562992Y0I3937J0D01*
G01D02*
X1930906D01*
G01X1562992Y-7874D02*
X1593701D01*
G01X1551181Y51181D02*
Y3937D01*
G01D02*
G03X1562992Y-7874I11811J0D01*
G01X1551181Y51181D02*
Y3937D01*
G01D02*
G03X1562992Y-7874I11811J0D01*
G01X1559055Y55118D02*
G03X1555118Y59055I-3937J0D01*
G01X1559055Y55118D02*
G03X1555118Y59055I-3937J0D01*
G01X1532996Y378885D02*
G03X1566807I16906J-13531D01*
G01X1532996D02*
G03X1566807I16906J-13531D01*
G01X1559882Y392016D02*
G03X1566807Y378885I37662J11471D01*
G01X1559882Y392016D02*
G03X1566807Y378885I37662J11471D01*
G01X1559882Y392016D02*
G03X1539921I-9980J-3039D01*
G01X1559882D02*
G03X1539921I-9980J-3039D01*
G01X1532996Y378885D02*
G03X1539921Y392016I-30737J24602D01*
G01X1532996Y378885D02*
G03X1539921Y392016I-30737J24602D01*
G01X1559882Y844772D02*
G03X1566807Y831641I37662J11471D01*
G01X1559882Y844772D02*
G03X1566807Y831641I37662J11471D01*
G01X1532996D02*
G03X1539921Y844772I-30737J24602D01*
G01X1532996Y831641D02*
G03X1539921Y844772I-30737J24602D01*
G01X1532996Y831641D02*
G03X1566807I16906J-13531D01*
G01X1532996D02*
G03X1566807I16906J-13531D01*
G01X1559882Y844772D02*
G03X1539921I-9980J-3040D01*
G01X1559882D02*
G03X1539921I-9980J-3039D01*
G01X1532996Y1284397D02*
G03X1566807I16906J-13531D01*
G01X1532996D02*
G03X1566807I16906J-13531D01*
G01X1559882Y1297528D02*
G03X1566807Y1284397I37662J11471D01*
G01X1559882Y1297528D02*
G03X1566807Y1284397I37662J11471D01*
G01X1559882Y1297528D02*
G03X1539921I-9980J-3040D01*
G01X1532996Y1284397D02*
G03X1539921Y1297528I-30737J24602D01*
G01X1532996Y1284397D02*
G03X1539921Y1297528I-30737J24602D01*
G01X1559882D02*
G03X1539921I-9980J-3040D01*
G01X1563976Y1382677D02*
G03Y1374803I0J-3937D01*
G01Y1382677D02*
G03Y1374803I0J-3937D01*
G01X1524606D02*
G03Y1382677I0J3937D01*
G01Y1374803D02*
G03Y1382677I0J3937D01*
G01X1864567D02*
X1563976D01*
G01X1864567D02*
X1563976D01*
G01X1593701Y-7874D02*
G03Y0I0J3937D01*
G01Y-7874D02*
G03Y0I0J3937D01*
G01X1633071D02*
G03Y-7874I0J-3937D01*
G01D02*
X1880512D01*
G01X1633071D02*
X1880512D01*
G01X1633071Y0D02*
G03Y-7874I0J-3937D01*
G01X1693996Y829921D02*
G03X1653839I-20078J0D01*
G01X1693996D02*
G03I-20079J0D01*
G01X1653839D02*
G03X1693996I20078J0D01*
G01X1781028Y378885D02*
G03X1814839I16906J-13531D01*
G01X1781028D02*
G03X1814838I16905J-13531D01*
G01X1807913Y392016D02*
G03X1814839Y378885I37662J11473D01*
G01X1807914Y392016D02*
G03X1814838Y378885I37663J11469D01*
G01X1807913Y392016D02*
G03X1787953I-9980J-3040D01*
G01X1807914D02*
G03X1787953I-9980J-3039D01*
G01X1781028Y378885D02*
G03X1787953Y392016I-30737J24602D01*
G01X1781028Y378885D02*
G03X1787953Y392016I-30737J24602D01*
G01X1807913Y844772D02*
G03X1814839Y831641I37662J11473D01*
G01X1807914Y844772D02*
G03X1814838Y831641I37663J11469D01*
G01X1781028D02*
G03X1787953Y844772I-30737J24602D01*
G01X1781028Y831641D02*
G03X1787953Y844772I-30737J24602D01*
G01X1781028Y831641D02*
G03X1814839I16906J-13531D01*
G01X1781028D02*
G03X1814838I16905J-13531D01*
G01X1807913Y844772D02*
G03X1787953I-9980J-3040D01*
G01X1807914D02*
G03X1787953I-9980J-3039D01*
G01X1781028Y1284397D02*
G03X1814839I16906J-13531D01*
G01X1781028D02*
G03X1814838I16905J-13531D01*
G01X1807913Y1297528D02*
G03X1814839Y1284397I37661J11473D01*
G01X1807914Y1297528D02*
G03X1814838Y1284397I37663J11469D01*
G01X1807913Y1297528D02*
G03X1787953I-9980J-3040D01*
G01X1781028Y1284397D02*
G03X1787953Y1297528I-30737J24602D01*
G01X1781028Y1284397D02*
G03X1787953Y1297528I-30737J24602D01*
G01X1807914D02*
G03X1787953I-9980J-3040D01*
G01X1911220Y0D02*
G03Y-7874I0J-3937D01*
G01Y0D02*
G03Y-7874I0J-3937D01*
G01X1880512D02*
G03Y0I0J3937D01*
G01Y-7874D02*
G03Y0I0J3937D01*
G01X1930906Y1382677D02*
X1895276D01*
G01D02*
G03Y1374803I0J-3937D01*
G01X1930906Y1382677D02*
X1895276D01*
G01D02*
G03Y1374803I0J-3937D01*
G01X1864567D02*
G03Y1382677I0J3937D01*
G01Y1374803D02*
G03Y1382677I0J3937D01*
G01X1919843Y-152756D02*
G03X1934843Y-137756I0J15000D01*
G01X1919843Y-152756D02*
G03X1934843Y-137756I0J15000D01*
G01Y-11811D02*
Y-137756D01*
G01Y-11811D02*
Y-137756D01*
G01X1930906Y0D02*
G03X1934843Y3937I0J3937D01*
G01X1930906Y0D02*
G03X1934843Y3937I0J3937D01*
G01Y-11811D02*
G03X1930906Y-7874I-3937J0D01*
G01X1934843Y-11811D02*
G03X1930906Y-7874I-3937J0D01*
G01X1911220D02*
X1930906D01*
G01X1911220D02*
X1930906D01*
G01X1934843Y1370866D02*
Y3937D01*
G01D02*
Y1370866D01*
G01D02*
G03X1930906Y1374803I-3937J0D01*
G01X1934843Y1370866D02*
G03X1930906Y1374803I-3937J0D01*
G01Y1382677D02*
G03X1934843Y1386614I0J3937D01*
G01X1930906Y1382677D02*
G03X1934843Y1386614I0J3937D01*
G01D02*
Y1643268D01*
G01Y1386614D02*
Y1643268D01*
G01D02*
G03X1919843Y1658268I-15000J0D01*
G01X1934843Y1643268D02*
G03X1919843Y1658268I-15000J0D01*
M02*
